FILE_TYPE = MACRO_DRAWING;
SET COLOR_WIRE YELLOW;
SET COLOR_PROP MONO;
SET COLOR_DOT WHITE;
SET COLOR_ARC YELLOW;
SET COLOR_BODY GREEN;
SET COLOR_NOTE MONO;
SET PROP_DISPLAY VALUE;
SET PAGE_NUMBER P216;
FORCEADD PVDDQ_ABC..1
(4000 2050);
FORCEPROP 3 LASTPIN (4000 2000) SIG_NAME PVDDQ_ABC\g
J 0
(4010 2010);
DISPLAY 0.659574 (4010 2010);
PAINT MONO (4010 2010);
DISPLAY INVISIBLE (4010 2010);
FORCEPROP 1 LAST VOLTAGE 1.2V
J 0
(3955 2007);
DISPLAY 0.340426 (3955 2007);
PAINT SKYBLUE (3955 2007);
DISPLAY INVISIBLE (3955 2007);
FORCEPROP 1 LAST BODY_TYPE PLUMBING
J 0
(3955 2007);
DISPLAY 0.340426 (3955 2007);
PAINT GREEN (3955 2007);
DISPLAY INVISIBLE (3955 2007);
FORCEPROP 1 LAST HDL_POWER PVDDQ_ABC
J 1
(4000 2100);
DISPLAY 0.872340 (4000 2100);
PAINT GREEN (4000 2100);
DISPLAY INVISIBLE (4000 2100);
FORCEPROP 1 LAST PATH I1
J 0
(4050 2075);
DISPLAY 0.872340 (4050 2075);
PAINT AQUA (4050 2075);
DISPLAY INVISIBLE (4050 2075);
FORCEPROP 2 LAST CDS_LIB mstr_symbols
J 0
(4000 2050);
PAINT ORANGE (4000 2050);
DISPLAY INVISIBLE (4000 2050);
FORCEADD IR354XX..1
(1425 2250);
FORCEPROP 2 LASTPIN (925 1950) $PN 33
J 2
(915 1960);
DISPLAY 0.617021 (915 1960);
PAINT ORANGE (915 1960);
FORCEPROP 2 LASTPIN (1925 1750) $PN 7
J 0
(1935 1760);
DISPLAY 0.617021 (1935 1760);
PAINT ORANGE (1935 1760);
FORCEPROP 2 LASTPIN (1925 1700) $PN 5
J 0
(1935 1710);
DISPLAY 0.617021 (1935 1710);
PAINT ORANGE (1935 1710);
FORCEPROP 2 LASTPIN (1925 1950) $PN 10
J 0
(1935 1960);
DISPLAY 0.617021 (1935 1960);
PAINT ORANGE (1935 1960);
FORCEPROP 2 LASTPIN (1925 1800) $PN 40
J 0
(1935 1810);
DISPLAY 0.617021 (1935 1810);
PAINT ORANGE (1935 1810);
FORCEPROP 2 LASTPIN (1925 1850) $PN 2
J 0
(1935 1860);
DISPLAY 0.617021 (1935 1860);
PAINT ORANGE (1935 1860);
FORCEPROP 2 LASTPIN (925 2150) $PN 34
J 2
(915 2160);
DISPLAY 0.617021 (915 2160);
PAINT ORANGE (915 2160);
FORCEPROP 2 LASTPIN (925 2250) $PN 6
J 2
(915 2260);
DISPLAY 0.617021 (915 2260);
PAINT ORANGE (915 2260);
FORCEPROP 2 LASTPIN (925 2050) $PN 39
J 2
(915 2060);
DISPLAY 0.617021 (915 2060);
PAINT ORANGE (915 2060);
FORCEPROP 2 LASTPIN (925 2400) $PN 1
J 2
(915 2410);
DISPLAY 0.617021 (915 2410);
PAINT ORANGE (915 2410);
FORCEPROP 2 LASTPIN (925 2500) $PN 35
J 2
(915 2510);
DISPLAY 0.617021 (915 2510);
PAINT ORANGE (915 2510);
FORCEPROP 2 LASTPIN (925 2300) $PN 41
J 2
(915 2310);
DISPLAY 0.617021 (915 2310);
PAINT ORANGE (915 2310);
FORCEPROP 2 LASTPIN (925 2750) $PN 30
J 2
(915 2760);
DISPLAY 0.617021 (915 2760);
PAINT ORANGE (915 2760);
FORCEPROP 2 LASTPIN (925 2700) $PN 25
J 2
(915 2710);
DISPLAY 0.617021 (915 2710);
PAINT ORANGE (915 2710);
FORCEPROP 2 LASTPIN (925 2600) $PN 4
J 2
(915 2610);
DISPLAY 0.617021 (915 2610);
PAINT ORANGE (915 2610);
FORCEPROP 2 LASTPIN (925 2800) $PN 3
J 2
(915 2810);
DISPLAY 0.617021 (915 2810);
PAINT ORANGE (915 2810);
FORCEPROP 2 LAST NO_XNET_CONNECTION 1
J 0
(975 3100);
PAINT MONO (975 3100);
FORCEPROP 1 LAST MATERIAL IC
J 0
(975 3000);
DISPLAY 0.617021 (975 3000);
PAINT SKYBLUE (975 3000);
FORCEPROP 1 LAST LOCATION EU7G2
J 0
(975 3050);
DISPLAY 0.617021 (975 3050);
PAINT AQUA (975 3050);
FORCEPROP 1 LAST VALUE IR35411
J 1
(1425 2875);
DISPLAY 0.617021 (1425 2875);
PAINT SKYBLUE (1425 2875);
FORCEPROP 2 LASTPIN (1925 2550) $PN 31
J 0
(1935 2560);
DISPLAY 0.617021 (1935 2560);
PAINT ORANGE (1935 2560);
FORCEPROP 2 LASTPIN (1925 2600) $PN 37
J 0
(1935 2610);
DISPLAY 0.617021 (1935 2610);
PAINT ORANGE (1935 2610);
FORCEPROP 2 LASTPIN (1925 2800) $PN 38
J 0
(1935 2810);
DISPLAY 0.617021 (1935 2810);
PAINT ORANGE (1935 2810);
FORCEPROP 2 LASTPIN (1925 2300) $PN 36
J 0
(1935 2310);
DISPLAY 0.617021 (1935 2310);
PAINT ORANGE (1935 2310);
FORCEPROP 2 LASTPIN (925 1900) $PN 32
J 2
(915 1910);
DISPLAY 0.617021 (915 1910);
PAINT ORANGE (915 1910);
FORCEPROP 1 LAST PART_NUMBER H73688-001
J 0
(1075 1550);
DISPLAY 0.617021 (1075 1550);
PAINT BLUE (1075 1550);
FORCEPROP 2 LAST CDS_LOCATION EU7G2
J 0
(975 3050);
DISPLAY 0.617021 (975 3050);
PAINT AQUA (975 3050);
DISPLAY INVISIBLE (975 3050);
FORCEPROP 2 LAST SEC 1
J 0
(975 3100);
DISPLAY 0.680851 (975 3100);
PAINT MONO (975 3100);
DISPLAY INVISIBLE (975 3100);
FORCEPROP 2 LAST SEC_TYPE SM
J 0
(975 3100);
DISPLAY 1.021277 (975 3100);
PAINT ORANGE (975 3100);
DISPLAY INVISIBLE (975 3100);
FORCEPROP 1 LAST PACK_TYPE SM
J 0
(975 3100);
PAINT SKYBLUE (975 3100);
DISPLAY INVISIBLE (975 3100);
FORCEPROP 1 LAST PATH I102
J 0
(1425 3000);
PAINT GREEN (1425 3000);
DISPLAY INVISIBLE (1425 3000);
FORCEPROP 2 LAST CDS_LIB mstr_discrete
J 0
(1425 2250);
PAINT ORANGE (1425 2250);
DISPLAY INVISIBLE (1425 2250);
FORCEADD IR354XX..1
(1425 -125);
FORCEPROP 2 LASTPIN (925 375) $PN 30
J 2
(915 385);
DISPLAY 0.617021 (915 385);
PAINT ORANGE (915 385);
FORCEPROP 2 LASTPIN (925 325) $PN 25
J 2
(915 335);
DISPLAY 0.617021 (915 335);
PAINT ORANGE (915 335);
FORCEPROP 2 LASTPIN (1925 -75) $PN 36
J 0
(1935 -65);
DISPLAY 0.617021 (1935 -65);
PAINT ORANGE (1935 -65);
FORCEPROP 2 LASTPIN (925 -475) $PN 32
J 2
(915 -465);
DISPLAY 0.617021 (915 -465);
PAINT ORANGE (915 -465);
FORCEPROP 2 LASTPIN (925 -325) $PN 39
J 2
(915 -315);
DISPLAY 0.617021 (915 -315);
PAINT ORANGE (915 -315);
FORCEPROP 2 LASTPIN (925 -425) $PN 33
J 2
(915 -415);
DISPLAY 0.617021 (915 -415);
PAINT ORANGE (915 -415);
FORCEPROP 2 LASTPIN (925 -75) $PN 41
J 2
(915 -65);
DISPLAY 0.617021 (915 -65);
PAINT ORANGE (915 -65);
FORCEPROP 2 LASTPIN (925 -225) $PN 34
J 2
(915 -215);
DISPLAY 0.617021 (915 -215);
PAINT ORANGE (915 -215);
FORCEPROP 2 LASTPIN (925 -125) $PN 6
J 2
(915 -115);
DISPLAY 0.617021 (915 -115);
PAINT ORANGE (915 -115);
FORCEPROP 2 LASTPIN (1925 -575) $PN 40
J 0
(1935 -565);
DISPLAY 0.617021 (1935 -565);
PAINT ORANGE (1935 -565);
FORCEPROP 2 LASTPIN (1925 -625) $PN 7
J 0
(1935 -615);
DISPLAY 0.617021 (1935 -615);
PAINT ORANGE (1935 -615);
FORCEPROP 2 LASTPIN (1925 -675) $PN 5
J 0
(1935 -665);
DISPLAY 0.617021 (1935 -665);
PAINT ORANGE (1935 -665);
FORCEPROP 2 LASTPIN (1925 -525) $PN 2
J 0
(1935 -515);
DISPLAY 0.617021 (1935 -515);
PAINT ORANGE (1935 -515);
FORCEPROP 2 LASTPIN (1925 -425) $PN 10
J 0
(1935 -415);
DISPLAY 0.617021 (1935 -415);
PAINT ORANGE (1935 -415);
FORCEPROP 2 LASTPIN (925 25) $PN 1
J 2
(915 35);
DISPLAY 0.617021 (915 35);
PAINT ORANGE (915 35);
FORCEPROP 2 LASTPIN (925 225) $PN 4
J 2
(915 235);
DISPLAY 0.617021 (915 235);
PAINT ORANGE (915 235);
FORCEPROP 2 LASTPIN (925 425) $PN 3
J 2
(915 435);
DISPLAY 0.617021 (915 435);
PAINT ORANGE (915 435);
FORCEPROP 1 LAST MATERIAL IC
J 0
(975 625);
DISPLAY 0.617021 (975 625);
PAINT SKYBLUE (975 625);
FORCEPROP 1 LAST VALUE IR35411
J 1
(1425 500);
DISPLAY 0.617021 (1425 500);
PAINT SKYBLUE (1425 500);
FORCEPROP 2 LASTPIN (1925 425) $PN 38
J 0
(1935 435);
DISPLAY 0.617021 (1935 435);
PAINT ORANGE (1935 435);
FORCEPROP 2 LASTPIN (1925 175) $PN 31
J 0
(1935 185);
DISPLAY 0.617021 (1935 185);
PAINT ORANGE (1935 185);
FORCEPROP 2 LASTPIN (1925 225) $PN 37
J 0
(1935 235);
DISPLAY 0.617021 (1935 235);
PAINT ORANGE (1935 235);
FORCEPROP 2 LASTPIN (925 125) $PN 35
J 2
(915 135);
DISPLAY 0.617021 (915 135);
PAINT ORANGE (915 135);
FORCEPROP 1 LAST PART_NUMBER H73688-001
J 0
(975 -825);
DISPLAY 0.617021 (975 -825);
PAINT BLUE (975 -825);
FORCEPROP 1 LAST LOCATION EU7G3
J 0
(975 675);
DISPLAY 0.617021 (975 675);
PAINT AQUA (975 675);
FORCEPROP 2 LAST NO_XNET_CONNECTION 1
J 0
(975 725);
PAINT MONO (975 725);
FORCEPROP 2 LAST CDS_LIB mstr_discrete
J 0
(1425 -125);
PAINT ORANGE (1425 -125);
DISPLAY INVISIBLE (1425 -125);
FORCEPROP 2 LAST CDS_LOCATION EU7G3
J 0
(975 675);
DISPLAY 0.617021 (975 675);
PAINT AQUA (975 675);
DISPLAY INVISIBLE (975 675);
FORCEPROP 2 LAST SEC 1
J 0
(975 725);
DISPLAY 0.680851 (975 725);
PAINT MONO (975 725);
DISPLAY INVISIBLE (975 725);
FORCEPROP 2 LAST SEC_TYPE SM
J 0
(975 725);
DISPLAY 1.021277 (975 725);
PAINT ORANGE (975 725);
DISPLAY INVISIBLE (975 725);
FORCEPROP 1 LAST PACK_TYPE SM
J 0
(975 725);
PAINT SKYBLUE (975 725);
DISPLAY INVISIBLE (975 725);
FORCEPROP 1 LAST PATH I103
J 0
(1425 625);
PAINT GREEN (1425 625);
DISPLAY INVISIBLE (1425 625);
FORCEADD RES..2
(4225 2400);
FORCEPROP 1 LASTPIN (4225 2300) $PN 2
J 0
(4230 2310);
DISPLAY 0.617021 (4230 2310);
PAINT ORANGE (4230 2310);
FORCEPROP 1 LAST TOLERANCE 1%
J 0
(4270 2425);
DISPLAY 0.617021 (4270 2425);
PAINT SKYBLUE (4270 2425);
FORCEPROP 1 LASTPIN (4225 2500) $PN 1
J 0
(4230 2462);
DISPLAY 0.617021 (4230 2462);
PAINT ORANGE (4230 2462);
FORCEPROP 1 LAST WATTAGE 1/16W
J 0
(4265 2375);
DISPLAY 0.617021 (4265 2375);
PAINT SKYBLUE (4265 2375);
FORCEPROP 1 LAST PACK_TYPE 0402
J 0
(4265 2225);
DISPLAY 0.617021 (4265 2225);
PAINT SKYBLUE (4265 2225);
FORCEPROP 1 LAST VALUE 68.1K
J 0
(4270 2475);
DISPLAY 0.617021 (4270 2475);
PAINT SKYBLUE (4270 2475);
FORCEPROP 1 LAST PART_NUMBER G21796-187
J 0
(4265 2275);
DISPLAY 0.617021 (4265 2275);
PAINT BLUE (4265 2275);
FORCEPROP 1 LAST LOCATION R7G25
J 0
(4270 2525);
DISPLAY 0.617021 (4270 2525);
PAINT AQUA (4270 2525);
FORCEPROP 1 LAST MATERIAL EMPTY
J 0
(4265 2325);
DISPLAY 0.617021 (4265 2325);
PAINT RED (4265 2325);
FORCEPROP 2 LAST CDS_LIB mstr_discrete
J 0
(4225 2400);
PAINT ORANGE (4225 2400);
DISPLAY INVISIBLE (4225 2400);
FORCEPROP 1 LAST PATH I104
J 0
(4275 2575);
DISPLAY 0.978723 (4275 2575);
PAINT WHITE (4275 2575);
DISPLAY INVISIBLE (4275 2575);
FORCEPROP 0 LAST SEC 1
J 0
(4275 2575);
DISPLAY 0.680851 (4275 2575);
PAINT MONO (4275 2575);
DISPLAY INVISIBLE (4275 2575);
FORCEPROP 2 LAST SEC_TYPE 0402
J 0
(4275 2625);
DISPLAY 1.021277 (4275 2625);
PAINT ORANGE (4275 2625);
DISPLAY INVISIBLE (4275 2625);
FORCEADD GND..1
(4225 2100);
FORCEPROP 3 LASTPIN (4225 2150) SIG_NAME GND\g
J 0
(4235 2160);
DISPLAY 0.659574 (4235 2160);
PAINT MONO (4235 2160);
DISPLAY INVISIBLE (4235 2160);
FORCEPROP 2 LAST ROOM PVCCIN_CPU0_PWR_VR
J 0
(3675 2175);
DISPLAY 1.936170 (3675 2175);
PAINT ORANGE (3675 2175);
DISPLAY INVISIBLE (3675 2175);
FORCEPROP 2 LAST BOM_COST PROC_VRD_VCCIN_CPU0
J 0
(3850 2175);
DISPLAY 1.446809 (3850 2175);
PAINT MONO (3850 2175);
DISPLAY INVISIBLE (3850 2175);
FORCEPROP 1 LAST BODY_TYPE PLUMBING
J 0
(4180 2057);
DISPLAY 0.340426 (4180 2057);
PAINT GREEN (4180 2057);
DISPLAY INVISIBLE (4180 2057);
FORCEPROP 1 LAST VOLTAGE 0
J 0
(4225 2100);
PAINT SKYBLUE (4225 2100);
DISPLAY INVISIBLE (4225 2100);
FORCEPROP 2 LAST CDS_LIB mstr_symbols
J 0
(4225 2100);
PAINT ORANGE (4225 2100);
DISPLAY INVISIBLE (4225 2100);
FORCEPROP 1 LAST SIZE 1B
J 0
(4300 2050);
DISPLAY 1.723404 (4300 2050);
PAINT GREEN (4300 2050);
DISPLAY INVISIBLE (4300 2050);
FORCEPROP 1 LAST PATH I105
J 0
(4300 2100);
DISPLAY 0.872340 (4300 2100);
PAINT AQUA (4300 2100);
DISPLAY INVISIBLE (4300 2100);
FORCEPROP 1 LAST HDL_POWER GND
J 0
(4225 2250);
DISPLAY 1.723404 (4225 2250);
PAINT GREEN (4225 2250);
DISPLAY INVISIBLE (4225 2250);
FORCEADD RES..2
(4325 0);
FORCEPROP 1 LASTPIN (4325 -100) $PN 2
J 0
(4330 -90);
DISPLAY 0.617021 (4330 -90);
PAINT ORANGE (4330 -90);
FORCEPROP 1 LAST MATERIAL EMPTY
J 0
(4365 -75);
DISPLAY 0.617021 (4365 -75);
PAINT RED (4365 -75);
FORCEPROP 1 LAST PACK_TYPE 0402
J 0
(4365 -175);
DISPLAY 0.617021 (4365 -175);
PAINT SKYBLUE (4365 -175);
FORCEPROP 1 LAST PART_NUMBER G21796-187
J 0
(4365 -125);
DISPLAY 0.617021 (4365 -125);
PAINT BLUE (4365 -125);
FORCEPROP 1 LAST WATTAGE 1/16W
J 0
(4365 -25);
DISPLAY 0.617021 (4365 -25);
PAINT SKYBLUE (4365 -25);
FORCEPROP 1 LASTPIN (4325 100) $PN 1
J 0
(4330 62);
DISPLAY 0.617021 (4330 62);
PAINT ORANGE (4330 62);
FORCEPROP 1 LAST TOLERANCE 1%
J 0
(4370 25);
DISPLAY 0.617021 (4370 25);
PAINT SKYBLUE (4370 25);
FORCEPROP 1 LAST VALUE 68.1K
J 0
(4370 75);
DISPLAY 0.617021 (4370 75);
PAINT SKYBLUE (4370 75);
FORCEPROP 1 LAST LOCATION R7G30
J 0
(4370 125);
DISPLAY 0.617021 (4370 125);
PAINT AQUA (4370 125);
FORCEPROP 2 LAST CDS_LIB mstr_discrete
J 0
(4325 0);
PAINT ORANGE (4325 0);
DISPLAY INVISIBLE (4325 0);
FORCEPROP 1 LAST PATH I106
J 0
(4375 175);
DISPLAY 0.978723 (4375 175);
PAINT WHITE (4375 175);
DISPLAY INVISIBLE (4375 175);
FORCEPROP 0 LAST SEC 1
J 0
(4375 175);
DISPLAY 0.680851 (4375 175);
PAINT MONO (4375 175);
DISPLAY INVISIBLE (4375 175);
FORCEPROP 2 LAST SEC_TYPE 0402
J 0
(4375 225);
DISPLAY 1.021277 (4375 225);
PAINT ORANGE (4375 225);
DISPLAY INVISIBLE (4375 225);
FORCEADD GND..1
(4325 -225);
FORCEPROP 3 LASTPIN (4325 -175) SIG_NAME GND\g
J 0
(4335 -165);
DISPLAY 0.659574 (4335 -165);
PAINT MONO (4335 -165);
DISPLAY INVISIBLE (4335 -165);
FORCEPROP 2 LAST ROOM PVCCIN_CPU0_PWR_VR
J 0
(3775 -150);
DISPLAY 1.936170 (3775 -150);
PAINT ORANGE (3775 -150);
DISPLAY INVISIBLE (3775 -150);
FORCEPROP 2 LAST BOM_COST PROC_VRD_VCCIN_CPU0
J 0
(3950 -150);
DISPLAY 1.446809 (3950 -150);
PAINT MONO (3950 -150);
DISPLAY INVISIBLE (3950 -150);
FORCEPROP 1 LAST BODY_TYPE PLUMBING
J 0
(4280 -268);
DISPLAY 0.340426 (4280 -268);
PAINT GREEN (4280 -268);
DISPLAY INVISIBLE (4280 -268);
FORCEPROP 2 LAST CDS_LIB mstr_symbols
J 0
(4325 -225);
PAINT ORANGE (4325 -225);
DISPLAY INVISIBLE (4325 -225);
FORCEPROP 1 LAST VOLTAGE 0
J 0
(4325 -225);
PAINT SKYBLUE (4325 -225);
DISPLAY INVISIBLE (4325 -225);
FORCEPROP 1 LAST HDL_POWER GND
J 0
(4325 -75);
DISPLAY 1.723404 (4325 -75);
PAINT GREEN (4325 -75);
DISPLAY INVISIBLE (4325 -75);
FORCEPROP 1 LAST SIZE 1B
J 0
(4400 -275);
DISPLAY 1.723404 (4400 -275);
PAINT GREEN (4400 -275);
DISPLAY INVISIBLE (4400 -275);
FORCEPROP 1 LAST PATH I107
J 0
(4400 -225);
DISPLAY 0.872340 (4400 -225);
PAINT AQUA (4400 -225);
DISPLAY INVISIBLE (4400 -225);
FORCEADD CAP_A..1
(675 1750);
FORCEPROP 0 LAST STATUS NOPOP
J 0
(450 1650);
DISPLAY 1.021277 (450 1650);
PAINT ORANGE (450 1650);
FORCEPROP 1 LAST TOLERANCE 10%
J 0
(725 1700);
DISPLAY 0.617021 (725 1700);
PAINT SKYBLUE (725 1700);
FORCEPROP 1 LAST VOLTAGE 16V
J 0
(725 1750);
DISPLAY 0.617021 (725 1750);
PAINT SKYBLUE (725 1750);
FORCEPROP 1 LAST VALUE 0.1UF
J 0
(725 1800);
DISPLAY 0.617021 (725 1800);
PAINT SKYBLUE (725 1800);
FORCEPROP 1 LAST LOCATION CT51
J 0
(700 1825);
DISPLAY 0.617021 (700 1825);
PAINT AQUA (700 1825);
FORCEPROP 1 LAST PACK_TYPE 0402V
J 0
(725 1550);
DISPLAY 0.617021 (725 1550);
PAINT SKYBLUE (725 1550);
FORCEPROP 1 LAST PART_NUMBER A36096-030
J 0
(725 1600);
DISPLAY 0.617021 (725 1600);
PAINT BLUE (725 1600);
FORCEPROP 1 LAST MATERIAL X7R
J 0
(725 1650);
DISPLAY 0.617021 (725 1650);
PAINT SKYBLUE (725 1650);
FORCEPROP 2 LAST CDS_LIB dev_discrete
J 0
(675 1750);
PAINT MONO (675 1750);
DISPLAY INVISIBLE (675 1750);
FORCEPROP 1 LAST PATH I108
J 0
(725 1900);
DISPLAY 0.978723 (725 1900);
PAINT WHITE (725 1900);
DISPLAY INVISIBLE (725 1900);
FORCEPROP 2 LAST ROOM PVCCIN_CPU0_PWR_VR
J 0
(725 1900);
DISPLAY 1.361702 (725 1900);
PAINT ORANGE (725 1900);
DISPLAY INVISIBLE (725 1900);
FORCEPROP 1 LASTPIN (675 1850) $PN 1
J 0
(685 1830);
DISPLAY 0.787234 (685 1830);
PAINT ORANGE (685 1830);
DISPLAY INVISIBLE (685 1830);
FORCEPROP 1 LASTPIN (675 1650) $PN 2
J 0
(685 1630);
DISPLAY 0.787234 (685 1630);
PAINT ORANGE (685 1630);
DISPLAY INVISIBLE (685 1630);
FORCEADD GND..1
(675 1500);
FORCEPROP 3 LASTPIN (675 1550) SIG_NAME GND\g
J 0
(685 1560);
DISPLAY 0.659574 (685 1560);
PAINT MONO (685 1560);
DISPLAY INVISIBLE (685 1560);
FORCEPROP 2 LAST CDS_LIB mstr_symbols
J 0
(675 1500);
PAINT MONO (675 1500);
DISPLAY INVISIBLE (675 1500);
FORCEPROP 1 LAST PATH I109
J 0
(750 1500);
DISPLAY 0.872340 (750 1500);
PAINT AQUA (750 1500);
DISPLAY INVISIBLE (750 1500);
FORCEPROP 1 LAST HDL_POWER GND
J 0
(675 1650);
DISPLAY 1.723404 (675 1650);
PAINT GREEN (675 1650);
DISPLAY INVISIBLE (675 1650);
FORCEPROP 1 LAST VOLTAGE 0
J 0
(675 1500);
PAINT SKYBLUE (675 1500);
DISPLAY INVISIBLE (675 1500);
FORCEPROP 1 LAST SIZE 1B
J 0
(750 1450);
DISPLAY 1.723404 (750 1450);
PAINT GREEN (750 1450);
DISPLAY INVISIBLE (750 1450);
FORCEPROP 2 LAST BOM_COST PROC_VRD_VCCIN_CPU0
J 0
(300 1575);
DISPLAY 1.446809 (300 1575);
PAINT MONO (300 1575);
DISPLAY INVISIBLE (300 1575);
FORCEPROP 2 LAST ROOM PVCCIN_CPU0_PWR_VR
J 0
(125 1575);
DISPLAY 1.936170 (125 1575);
PAINT ORANGE (125 1575);
DISPLAY INVISIBLE (125 1575);
FORCEPROP 1 LAST BODY_TYPE PLUMBING
J 0
(630 1457);
DISPLAY 0.340426 (630 1457);
PAINT GREEN (630 1457);
DISPLAY INVISIBLE (630 1457);
FORCEADD CAP_A..1
(775 -625);
FORCEPROP 1 LAST PART_NUMBER A36096-030
J 0
(825 -775);
DISPLAY 0.617021 (825 -775);
PAINT BLUE (825 -775);
FORCEPROP 1 LAST MATERIAL X7R
J 0
(825 -725);
DISPLAY 0.617021 (825 -725);
PAINT SKYBLUE (825 -725);
FORCEPROP 0 LAST STATUS NOPOP
J 0
(550 -700);
DISPLAY 1.021277 (550 -700);
PAINT ORANGE (550 -700);
FORCEPROP 1 LAST PACK_TYPE 0402V
J 0
(825 -825);
DISPLAY 0.617021 (825 -825);
PAINT SKYBLUE (825 -825);
FORCEPROP 1 LAST TOLERANCE 10%
J 0
(825 -675);
DISPLAY 0.617021 (825 -675);
PAINT SKYBLUE (825 -675);
FORCEPROP 1 LAST VOLTAGE 16V
J 0
(825 -625);
DISPLAY 0.617021 (825 -625);
PAINT SKYBLUE (825 -625);
FORCEPROP 1 LAST VALUE 0.1UF
J 0
(825 -575);
DISPLAY 0.617021 (825 -575);
PAINT SKYBLUE (825 -575);
FORCEPROP 1 LAST LOCATION CT52
J 0
(650 -600);
DISPLAY 0.617021 (650 -600);
PAINT AQUA (650 -600);
FORCEPROP 2 LAST ROOM PVCCIN_CPU0_PWR_VR
J 0
(825 -475);
DISPLAY 1.361702 (825 -475);
PAINT ORANGE (825 -475);
DISPLAY INVISIBLE (825 -475);
FORCEPROP 1 LAST PATH I111
J 0
(825 -475);
DISPLAY 0.978723 (825 -475);
PAINT WHITE (825 -475);
DISPLAY INVISIBLE (825 -475);
FORCEPROP 2 LAST CDS_LIB dev_discrete
J 0
(775 -625);
PAINT MONO (775 -625);
DISPLAY INVISIBLE (775 -625);
FORCEPROP 1 LASTPIN (775 -525) $PN 1
J 0
(785 -545);
DISPLAY 0.787234 (785 -545);
PAINT ORANGE (785 -545);
DISPLAY INVISIBLE (785 -545);
FORCEPROP 1 LASTPIN (775 -725) $PN 2
J 0
(785 -745);
DISPLAY 0.787234 (785 -745);
PAINT ORANGE (785 -745);
DISPLAY INVISIBLE (785 -745);
FORCEADD GND..1
(775 -875);
FORCEPROP 3 LASTPIN (775 -825) SIG_NAME GND\g
J 0
(785 -815);
DISPLAY 0.659574 (785 -815);
PAINT MONO (785 -815);
DISPLAY INVISIBLE (785 -815);
FORCEPROP 1 LAST BODY_TYPE PLUMBING
J 0
(730 -918);
DISPLAY 0.340426 (730 -918);
PAINT GREEN (730 -918);
DISPLAY INVISIBLE (730 -918);
FORCEPROP 2 LAST ROOM PVCCIN_CPU0_PWR_VR
J 0
(225 -800);
DISPLAY 1.936170 (225 -800);
PAINT ORANGE (225 -800);
DISPLAY INVISIBLE (225 -800);
FORCEPROP 2 LAST BOM_COST PROC_VRD_VCCIN_CPU0
J 0
(400 -800);
DISPLAY 1.446809 (400 -800);
PAINT MONO (400 -800);
DISPLAY INVISIBLE (400 -800);
FORCEPROP 1 LAST SIZE 1B
J 0
(850 -925);
DISPLAY 1.723404 (850 -925);
PAINT GREEN (850 -925);
DISPLAY INVISIBLE (850 -925);
FORCEPROP 1 LAST VOLTAGE 0
J 0
(775 -875);
PAINT SKYBLUE (775 -875);
DISPLAY INVISIBLE (775 -875);
FORCEPROP 1 LAST HDL_POWER GND
J 0
(775 -725);
DISPLAY 1.723404 (775 -725);
PAINT GREEN (775 -725);
DISPLAY INVISIBLE (775 -725);
FORCEPROP 1 LAST PATH I112
J 0
(850 -875);
DISPLAY 0.872340 (850 -875);
PAINT AQUA (850 -875);
DISPLAY INVISIBLE (850 -875);
FORCEPROP 2 LAST CDS_LIB mstr_symbols
J 0
(775 -875);
PAINT MONO (775 -875);
DISPLAY INVISIBLE (775 -875);
FORCEADD 3D01R5F-GP..1
R 4
(2750 1475);
FORCEPROP 1 LAST LOCATION RT34
J 0
(2625 1420);
DISPLAY 0.617021 (2625 1420);
PAINT GREEN (2625 1420);
FORCEPROP 0 LAST STATUS NOPOP
J 0
(2500 1475);
DISPLAY 1.021277 (2500 1475);
PAINT ORANGE (2500 1475);
FORCEPROP 1 LAST VALUE 3D01R5F-GP
J 0
(2500 1350);
DISPLAY 0.617021 (2500 1350);
PAINT GREEN (2500 1350);
FORCEPROP 1 LAST CDS_LMAN_SYM_OUTLINE -50,75,50,-75
R 2
J 0
(2750 1475);
DISPLAY 0.468085 (2750 1475);
PAINT GREEN (2750 1475);
DISPLAY INVISIBLE (2750 1475);
FORCEPROP 1 LAST PATH I114
R 2
J 0
(2750 1475);
DISPLAY 0.617021 (2750 1475);
PAINT GREEN (2750 1475);
DISPLAY INVISIBLE (2750 1475);
FORCEPROP 2 LAST CDS_LIB w_hdl
J 0
(2750 1475);
PAINT MONO (2750 1475);
DISPLAY INVISIBLE (2750 1475);
FORCEPROP 1 LAST PART_NUMBER 64.3R015.16L
R 2
J 0
(2750 1475);
DISPLAY 0.617021 (2750 1475);
PAINT GREEN (2750 1475);
DISPLAY INVISIBLE (2750 1475);
FORCEPROP 1 LAST PACK_TYPE SMD-RG5
R 2
J 0
(2750 1475);
DISPLAY 0.617021 (2750 1475);
PAINT GREEN (2750 1475);
DISPLAY INVISIBLE (2750 1475);
FORCEPROP 2 LASTPIN (2750 1600) SIG_NAME UN$216$3D01R5F-GP$I114$2
J 0
(2760 1610);
DISPLAY 0.659574 (2760 1610);
PAINT MONO (2760 1610);
DISPLAY INVISIBLE (2760 1610);
FORCEADD GND..1
(2750 1225);
FORCEPROP 3 LASTPIN (2750 1275) SIG_NAME GND\g
J 0
(2760 1285);
DISPLAY 0.659574 (2760 1285);
PAINT MONO (2760 1285);
DISPLAY INVISIBLE (2760 1285);
FORCEPROP 2 LAST CDS_LIB mstr_symbols
J 0
(2750 1225);
PAINT MONO (2750 1225);
DISPLAY INVISIBLE (2750 1225);
FORCEPROP 1 LAST PATH I115
J 0
(2825 1225);
DISPLAY 0.872340 (2825 1225);
PAINT AQUA (2825 1225);
DISPLAY INVISIBLE (2825 1225);
FORCEPROP 1 LAST HDL_POWER GND
J 0
(2750 1375);
DISPLAY 1.723404 (2750 1375);
PAINT GREEN (2750 1375);
DISPLAY INVISIBLE (2750 1375);
FORCEPROP 1 LAST SIZE 1B
J 0
(2825 1175);
DISPLAY 1.723404 (2825 1175);
PAINT GREEN (2825 1175);
DISPLAY INVISIBLE (2825 1175);
FORCEPROP 1 LAST VOLTAGE 0
J 0
(2750 1225);
PAINT SKYBLUE (2750 1225);
DISPLAY INVISIBLE (2750 1225);
FORCEPROP 1 LAST BODY_TYPE PLUMBING
J 0
(2705 1182);
DISPLAY 0.340426 (2705 1182);
PAINT GREEN (2705 1182);
DISPLAY INVISIBLE (2705 1182);
FORCEPROP 2 LAST BOM_COST PROC_VRD_VCCIN_CPU0
J 0
(2375 1300);
DISPLAY 1.446809 (2375 1300);
PAINT MONO (2375 1300);
DISPLAY INVISIBLE (2375 1300);
FORCEPROP 2 LAST ROOM PVCCIN_CPU0_PWR_VR
J 0
(2200 1300);
DISPLAY 1.936170 (2200 1300);
PAINT ORANGE (2200 1300);
DISPLAY INVISIBLE (2200 1300);
FORCEADD GND..1
(2650 2125);
FORCEPROP 3 LASTPIN (2650 2175) SIG_NAME GND\g
J 0
(2660 2185);
DISPLAY 0.659574 (2660 2185);
PAINT MONO (2660 2185);
DISPLAY INVISIBLE (2660 2185);
FORCEPROP 2 LAST ROOM VDDQ_KLM_PWR_VR
J 0
(2075 2200);
DISPLAY 1.361702 (2075 2200);
PAINT ORANGE (2075 2200);
DISPLAY INVISIBLE (2075 2200);
FORCEPROP 1 LAST VOLTAGE 0
J 0
(2650 2125);
PAINT SKYBLUE (2650 2125);
DISPLAY INVISIBLE (2650 2125);
FORCEPROP 1 LAST BODY_TYPE PLUMBING
J 0
(2605 2082);
DISPLAY 0.340426 (2605 2082);
PAINT GREEN (2605 2082);
DISPLAY INVISIBLE (2605 2082);
FORCEPROP 1 LAST SIZE 1B
J 0
(2725 2075);
DISPLAY 1.170213 (2725 2075);
PAINT AQUA (2725 2075);
DISPLAY INVISIBLE (2725 2075);
FORCEPROP 1 LAST HDL_POWER GND
J 0
(2650 2275);
DISPLAY 1.170213 (2650 2275);
PAINT GREEN (2650 2275);
DISPLAY INVISIBLE (2650 2275);
FORCEPROP 1 LAST PATH I117
J 0
(2725 2125);
DISPLAY 0.872340 (2725 2125);
PAINT AQUA (2725 2125);
DISPLAY INVISIBLE (2725 2125);
FORCEPROP 2 LAST CDS_LIB mstr_symbols
J 0
(2650 2125);
PAINT MONO (2650 2125);
DISPLAY INVISIBLE (2650 2125);
FORCEADD CAP..1
(2650 2325);
FORCEPROP 1 LAST LOCATION CT49
J 0
(2500 2325);
DISPLAY 0.617021 (2500 2325);
PAINT AQUA (2500 2325);
FORCEPROP 1 LAST TOLERANCE 10%
J 0
(2700 2275);
DISPLAY 0.617021 (2700 2275);
PAINT SKYBLUE (2700 2275);
FORCEPROP 1 LAST VOLTAGE 50V
J 0
(2700 2325);
DISPLAY 0.617021 (2700 2325);
PAINT SKYBLUE (2700 2325);
FORCEPROP 1 LAST VALUE 1000PF
J 0
(2700 2375);
DISPLAY 0.617021 (2700 2375);
PAINT SKYBLUE (2700 2375);
FORCEPROP 1 LAST MATERIAL X7R
J 0
(2700 2225);
DISPLAY 0.617021 (2700 2225);
PAINT SKYBLUE (2700 2225);
FORCEPROP 1 LAST PACK_TYPE 0402LF
J 0
(2700 2125);
DISPLAY 0.617021 (2700 2125);
PAINT SKYBLUE (2700 2125);
FORCEPROP 1 LAST PART_NUMBER A36096-046
J 0
(2700 2175);
DISPLAY 0.617021 (2700 2175);
PAINT BLUE (2700 2175);
FORCEPROP 0 LAST STATUS NOPOP
J 0
(2425 2225);
DISPLAY 1.021277 (2425 2225);
PAINT ORANGE (2425 2225);
FORCEPROP 0 LAST ROOM VDDQ_KLM_PWR_VR
J 0
(2700 2525);
DISPLAY 1.021277 (2700 2525);
PAINT ORANGE (2700 2525);
DISPLAY INVISIBLE (2700 2525);
FORCEPROP 1 LAST PATH I118
J 0
(2700 2475);
DISPLAY 0.978723 (2700 2475);
PAINT WHITE (2700 2475);
DISPLAY INVISIBLE (2700 2475);
FORCEPROP 2 LAST CDS_LIB mstr_discrete
J 0
(2650 2325);
PAINT MONO (2650 2325);
DISPLAY INVISIBLE (2650 2325);
FORCEPROP 1 LASTPIN (2650 2225) $PN 2
J 0
(2660 2205);
DISPLAY 0.787234 (2660 2205);
PAINT ORANGE (2660 2205);
DISPLAY INVISIBLE (2660 2205);
FORCEPROP 1 LASTPIN (2650 2425) $PN 1
J 0
(2660 2405);
DISPLAY 0.787234 (2660 2405);
PAINT ORANGE (2660 2405);
DISPLAY INVISIBLE (2660 2405);
FORCEADD SC2K2P50V3KX-GP..1
(2700 -600);
FORCEPROP 1 LAST VALUE SC2K2P50V3KX-GP
J 0
(2725 -650);
DISPLAY 0.617021 (2725 -650);
PAINT GREEN (2725 -650);
FORCEPROP 1 LAST LOCATION CT53
J 0
(2725 -570);
DISPLAY 0.617021 (2725 -570);
PAINT GREEN (2725 -570);
FORCEPROP 0 LAST STATUS NOPOP
J 0
(2450 -625);
DISPLAY 1.021277 (2450 -625);
PAINT ORANGE (2450 -625);
FORCEPROP 2 LAST CDS_LIB w_hdl
J 0
(2700 -600);
PAINT MONO (2700 -600);
DISPLAY INVISIBLE (2700 -600);
FORCEPROP 1 LAST PATH I119
J 0
(2700 -600);
DISPLAY 0.617021 (2700 -600);
PAINT GREEN (2700 -600);
DISPLAY INVISIBLE (2700 -600);
FORCEPROP 1 LAST CDS_LMAN_SYM_OUTLINE -50,25,50,-25
J 0
(2700 -600);
DISPLAY 0.468085 (2700 -600);
PAINT GREEN (2700 -600);
DISPLAY INVISIBLE (2700 -600);
FORCEPROP 1 LAST PART_NUMBER 78.22224.2BL
J 0
(2700 -600);
DISPLAY 0.617021 (2700 -600);
PAINT GREEN (2700 -600);
DISPLAY INVISIBLE (2700 -600);
FORCEPROP 1 LAST PACK_TYPE SMD-BCG6
J 0
(2700 -600);
DISPLAY 0.617021 (2700 -600);
PAINT GREEN (2700 -600);
DISPLAY INVISIBLE (2700 -600);
FORCEADD GND..1
(2700 -1150);
FORCEPROP 3 LASTPIN (2700 -1100) SIG_NAME GND\g
J 0
(2710 -1090);
DISPLAY 0.659574 (2710 -1090);
PAINT MONO (2710 -1090);
DISPLAY INVISIBLE (2710 -1090);
FORCEPROP 2 LAST CDS_LIB mstr_symbols
J 0
(2700 -1150);
PAINT MONO (2700 -1150);
DISPLAY INVISIBLE (2700 -1150);
FORCEPROP 1 LAST PATH I120
J 0
(2775 -1150);
DISPLAY 0.872340 (2775 -1150);
PAINT AQUA (2775 -1150);
DISPLAY INVISIBLE (2775 -1150);
FORCEPROP 2 LAST ROOM PVCCIN_CPU0_PWR_VR
J 0
(2150 -1075);
DISPLAY 1.936170 (2150 -1075);
PAINT ORANGE (2150 -1075);
DISPLAY INVISIBLE (2150 -1075);
FORCEPROP 2 LAST BOM_COST PROC_VRD_VCCIN_CPU0
J 0
(2325 -1075);
DISPLAY 1.446809 (2325 -1075);
PAINT MONO (2325 -1075);
DISPLAY INVISIBLE (2325 -1075);
FORCEPROP 1 LAST BODY_TYPE PLUMBING
J 0
(2655 -1193);
DISPLAY 0.340426 (2655 -1193);
PAINT GREEN (2655 -1193);
DISPLAY INVISIBLE (2655 -1193);
FORCEPROP 1 LAST VOLTAGE 0
J 0
(2700 -1150);
PAINT SKYBLUE (2700 -1150);
DISPLAY INVISIBLE (2700 -1150);
FORCEPROP 1 LAST SIZE 1B
J 0
(2775 -1200);
DISPLAY 1.723404 (2775 -1200);
PAINT GREEN (2775 -1200);
DISPLAY INVISIBLE (2775 -1200);
FORCEPROP 1 LAST HDL_POWER GND
J 0
(2700 -1000);
DISPLAY 1.723404 (2700 -1000);
PAINT GREEN (2700 -1000);
DISPLAY INVISIBLE (2700 -1000);
FORCEADD CAP..1
(2550 -125);
FORCEPROP 1 LAST VALUE 1000PF
J 0
(2600 -75);
DISPLAY 0.617021 (2600 -75);
PAINT SKYBLUE (2600 -75);
FORCEPROP 1 LAST PACK_TYPE 0402LF
J 0
(2600 -325);
DISPLAY 0.617021 (2600 -325);
PAINT SKYBLUE (2600 -325);
FORCEPROP 1 LAST VOLTAGE 50V
J 0
(2600 -125);
DISPLAY 0.617021 (2600 -125);
PAINT SKYBLUE (2600 -125);
FORCEPROP 1 LAST LOCATION CT54
J 0
(2400 -125);
DISPLAY 0.617021 (2400 -125);
PAINT AQUA (2400 -125);
FORCEPROP 1 LAST TOLERANCE 10%
J 0
(2600 -175);
DISPLAY 0.617021 (2600 -175);
PAINT SKYBLUE (2600 -175);
FORCEPROP 0 LAST STATUS NOPOP
J 0
(2325 -200);
DISPLAY 1.021277 (2325 -200);
PAINT ORANGE (2325 -200);
FORCEPROP 1 LAST MATERIAL X7R
J 0
(2600 -225);
DISPLAY 0.617021 (2600 -225);
PAINT SKYBLUE (2600 -225);
FORCEPROP 1 LAST PART_NUMBER A36096-046
J 0
(2600 -275);
DISPLAY 0.617021 (2600 -275);
PAINT BLUE (2600 -275);
FORCEPROP 0 LAST ROOM VDDQ_KLM_PWR_VR
J 0
(2600 75);
DISPLAY 1.021277 (2600 75);
PAINT ORANGE (2600 75);
DISPLAY INVISIBLE (2600 75);
FORCEPROP 1 LAST PATH I121
J 0
(2600 25);
DISPLAY 0.978723 (2600 25);
PAINT WHITE (2600 25);
DISPLAY INVISIBLE (2600 25);
FORCEPROP 2 LAST CDS_LIB mstr_discrete
J 0
(2550 -125);
PAINT MONO (2550 -125);
DISPLAY INVISIBLE (2550 -125);
FORCEPROP 1 LASTPIN (2550 -225) $PN 2
J 0
(2560 -245);
DISPLAY 0.787234 (2560 -245);
PAINT ORANGE (2560 -245);
DISPLAY INVISIBLE (2560 -245);
FORCEPROP 1 LASTPIN (2550 -25) $PN 1
J 0
(2560 -45);
DISPLAY 0.787234 (2560 -45);
PAINT ORANGE (2560 -45);
DISPLAY INVISIBLE (2560 -45);
FORCEADD GND..1
(2550 -325);
FORCEPROP 3 LASTPIN (2550 -275) SIG_NAME GND\g
J 0
(2560 -265);
DISPLAY 0.659574 (2560 -265);
PAINT MONO (2560 -265);
DISPLAY INVISIBLE (2560 -265);
FORCEPROP 1 LAST HDL_POWER GND
J 0
(2550 -175);
DISPLAY 1.170213 (2550 -175);
PAINT GREEN (2550 -175);
DISPLAY INVISIBLE (2550 -175);
FORCEPROP 1 LAST SIZE 1B
J 0
(2625 -375);
DISPLAY 1.170213 (2625 -375);
PAINT AQUA (2625 -375);
DISPLAY INVISIBLE (2625 -375);
FORCEPROP 1 LAST BODY_TYPE PLUMBING
J 0
(2505 -368);
DISPLAY 0.340426 (2505 -368);
PAINT GREEN (2505 -368);
DISPLAY INVISIBLE (2505 -368);
FORCEPROP 1 LAST VOLTAGE 0
J 0
(2550 -325);
PAINT SKYBLUE (2550 -325);
DISPLAY INVISIBLE (2550 -325);
FORCEPROP 2 LAST ROOM VDDQ_KLM_PWR_VR
J 0
(1975 -250);
DISPLAY 1.361702 (1975 -250);
PAINT ORANGE (1975 -250);
DISPLAY INVISIBLE (1975 -250);
FORCEPROP 1 LAST PATH I122
J 0
(2625 -325);
DISPLAY 0.872340 (2625 -325);
PAINT AQUA (2625 -325);
DISPLAY INVISIBLE (2625 -325);
FORCEPROP 2 LAST CDS_LIB mstr_symbols
J 0
(2550 -325);
PAINT MONO (2550 -325);
DISPLAY INVISIBLE (2550 -325);
FORCEADD 3D01R5F-GP..1
R 4
(2700 -900);
FORCEPROP 0 LAST STATUS NOPOP
J 0
(2475 -850);
DISPLAY 1.021277 (2475 -850);
PAINT ORANGE (2475 -850);
FORCEPROP 1 LAST VALUE 3D01R5F-GP
J 0
(2475 -950);
DISPLAY 0.617021 (2475 -950);
PAINT GREEN (2475 -950);
FORCEPROP 1 LAST LOCATION RT35
J 0
(2575 -905);
DISPLAY 0.617021 (2575 -905);
PAINT GREEN (2575 -905);
FORCEPROP 1 LAST CDS_LMAN_SYM_OUTLINE -50,75,50,-75
R 2
J 0
(2700 -900);
DISPLAY 0.468085 (2700 -900);
PAINT GREEN (2700 -900);
DISPLAY INVISIBLE (2700 -900);
FORCEPROP 1 LAST PATH I123
R 2
J 0
(2700 -900);
DISPLAY 0.617021 (2700 -900);
PAINT GREEN (2700 -900);
DISPLAY INVISIBLE (2700 -900);
FORCEPROP 2 LAST CDS_LIB w_hdl
J 0
(2700 -900);
PAINT MONO (2700 -900);
DISPLAY INVISIBLE (2700 -900);
FORCEPROP 1 LAST PART_NUMBER 64.3R015.16L
R 2
J 0
(2700 -900);
DISPLAY 0.617021 (2700 -900);
PAINT GREEN (2700 -900);
DISPLAY INVISIBLE (2700 -900);
FORCEPROP 1 LAST PACK_TYPE SMD-RG5
R 2
J 0
(2700 -900);
DISPLAY 0.617021 (2700 -900);
PAINT GREEN (2700 -900);
DISPLAY INVISIBLE (2700 -900);
FORCEPROP 2 LASTPIN (2700 -775) SIG_NAME UN$216$3D01R5F-GP$I123$2
J 0
(2710 -765);
DISPLAY 0.659574 (2710 -765);
PAINT MONO (2710 -765);
DISPLAY INVISIBLE (2710 -765);
FORCEADD SC2K2P50V3KX-GP..1
(2750 1800);
FORCEPROP 1 LAST VALUE SC2K2P50V3KX-GP
J 0
(2775 1750);
DISPLAY 0.617021 (2775 1750);
PAINT GREEN (2775 1750);
FORCEPROP 1 LAST LOCATION CT50
J 0
(2775 1830);
DISPLAY 0.617021 (2775 1830);
PAINT GREEN (2775 1830);
FORCEPROP 0 LAST STATUS NOPOP
J 0
(2500 1725);
DISPLAY 1.021277 (2500 1725);
PAINT ORANGE (2500 1725);
FORCEPROP 2 LAST CDS_LIB w_hdl
J 0
(2750 1800);
PAINT MONO (2750 1800);
DISPLAY INVISIBLE (2750 1800);
FORCEPROP 1 LAST CDS_LMAN_SYM_OUTLINE -50,25,50,-25
J 0
(2750 1800);
DISPLAY 0.468085 (2750 1800);
PAINT GREEN (2750 1800);
DISPLAY INVISIBLE (2750 1800);
FORCEPROP 1 LAST PACK_TYPE SMD-BCG6
J 0
(2750 1800);
DISPLAY 0.617021 (2750 1800);
PAINT GREEN (2750 1800);
DISPLAY INVISIBLE (2750 1800);
FORCEPROP 1 LAST PART_NUMBER 78.22224.2BL
J 0
(2750 1800);
DISPLAY 0.617021 (2750 1800);
PAINT GREEN (2750 1800);
DISPLAY INVISIBLE (2750 1800);
FORCEPROP 1 LAST PATH I124
J 0
(2750 1800);
DISPLAY 0.617021 (2750 1800);
PAINT GREEN (2750 1800);
DISPLAY INVISIBLE (2750 1800);
FORCEADD INDUCTOR..1
(3175 1950);
FORCEPROP 1 LAST VALUE 0.12UH
J 2
(3170 1840);
DISPLAY 0.617021 (3170 1840);
PAINT SKYBLUE (3170 1840);
FORCEPROP 1 LAST PACK_TYPE SM
J 0
(3340 1840);
DISPLAY 0.617021 (3340 1840);
PAINT SKYBLUE (3340 1840);
FORCEPROP 1 LASTPIN (3075 1950) $PN 1
J 0
(3075 1960);
DISPLAY 0.617021 (3075 1960);
PAINT WHITE (3075 1960);
FORCEPROP 1 LAST LOCATION L7G1
J 0
(3075 2000);
DISPLAY 0.617021 (3075 2000);
PAINT AQUA (3075 2000);
FORCEPROP 1 LAST MATERIAL IND
J 0
(3215 1840);
DISPLAY 0.617021 (3215 1840);
PAINT SKYBLUE (3215 1840);
FORCEPROP 1 LAST PART_NUMBER D92183-034
J 0
(3050 1900);
DISPLAY 0.617021 (3050 1900);
PAINT BLUE (3050 1900);
FORCEPROP 1 LASTPIN (3275 1950) $PN 2
J 2
(3285 1960);
DISPLAY 0.617021 (3285 1960);
PAINT WHITE (3285 1960);
FORCEPROP 0 LAST CDS_SEC 1
J 0
(3075 2050);
PAINT MONO (3075 2050);
DISPLAY INVISIBLE (3075 2050);
FORCEPROP 2 LAST CDS_LOCATION L7G1
J 0
(3075 2000);
DISPLAY 0.617021 (3075 2000);
PAINT AQUA (3075 2000);
DISPLAY INVISIBLE (3075 2000);
FORCEPROP 2 LAST CDS_LIB mstr_discrete
J 0
(3175 1950);
PAINT ORANGE (3175 1950);
DISPLAY INVISIBLE (3175 1950);
FORCEPROP 2 LAST ROOM VDDQ_ABC_PWR_VR
J 0
(3075 2050);
DISPLAY 1.361702 (3075 2050);
PAINT ORANGE (3075 2050);
DISPLAY INVISIBLE (3075 2050);
FORCEPROP 2 LAST SEC 1
J 0
(3075 2175);
DISPLAY 0.680851 (3075 2175);
PAINT MONO (3075 2175);
DISPLAY INVISIBLE (3075 2175);
FORCEPROP 2 LAST SEC_TYPE SM
J 0
(3075 2175);
DISPLAY 1.021277 (3075 2175);
PAINT ORANGE (3075 2175);
DISPLAY INVISIBLE (3075 2175);
FORCEPROP 1 LAST PATH I125
J 0
(3075 2100);
DISPLAY 0.978723 (3075 2100);
PAINT ORANGE (3075 2100);
DISPLAY INVISIBLE (3075 2100);
FORCEADD RES..1
(-275 2025);
FORCEPROP 1 LAST LOCATION RT33
J 0
(-325 2050);
DISPLAY 0.617021 (-325 2050);
PAINT AQUA (-325 2050);
FORCEPROP 1 LAST WATTAGE 1/16W
J 2
(-300 1875);
DISPLAY 0.617021 (-300 1875);
PAINT SKYBLUE (-300 1875);
FORCEPROP 1 LAST PACK_TYPE 0402
J 0
(-175 1875);
DISPLAY 0.617021 (-175 1875);
PAINT SKYBLUE (-175 1875);
FORCEPROP 1 LAST MATERIAL CHIP
J 0
(-275 1875);
DISPLAY 0.617021 (-275 1875);
PAINT SKYBLUE (-275 1875);
FORCEPROP 1 LAST TOLERANCE 5%
J 0
(-275 1925);
DISPLAY 0.617021 (-275 1925);
PAINT SKYBLUE (-275 1925);
FORCEPROP 1 LAST VALUE 0.0
J 2
(-300 1925);
DISPLAY 0.617021 (-300 1925);
PAINT SKYBLUE (-300 1925);
FORCEPROP 1 LAST PART_NUMBER G21497-005
J 0
(-375 1975);
DISPLAY 0.617021 (-375 1975);
PAINT BLUE (-375 1975);
FORCEPROP 2 LAST CDS_LIB mstr_discrete
J 0
(-275 2025);
PAINT MONO (-275 2025);
DISPLAY INVISIBLE (-275 2025);
FORCEPROP 1 LAST PATH I126
J 0
(-325 2175);
DISPLAY 0.978723 (-325 2175);
PAINT WHITE (-325 2175);
DISPLAY INVISIBLE (-325 2175);
FORCEPROP 2 LAST BOM_COST DEBUG
J 0
(-325 2225);
DISPLAY 1.021277 (-325 2225);
PAINT ORANGE (-325 2225);
DISPLAY INVISIBLE (-325 2225);
FORCEPROP 2 LAST ROOM BMC_DEBUG_HEADER
J 0
(-325 2175);
DISPLAY 1.021277 (-325 2175);
PAINT ORANGE (-325 2175);
DISPLAY INVISIBLE (-325 2175);
FORCEPROP 1 LASTPIN (-375 2025) $PN 1
J 0
(-363 2037);
DISPLAY 0.787234 (-363 2037);
PAINT ORANGE (-363 2037);
DISPLAY INVISIBLE (-363 2037);
FORCEPROP 1 LASTPIN (-175 2025) $PN 2
J 0
(-213 2037);
DISPLAY 0.787234 (-213 2037);
PAINT ORANGE (-213 2037);
DISPLAY INVISIBLE (-213 2037);
FORCEADD RES..1
(-225 -325);
FORCEPROP 1 LAST WATTAGE 1/16W
J 2
(-250 -475);
DISPLAY 0.617021 (-250 -475);
PAINT SKYBLUE (-250 -475);
FORCEPROP 1 LAST VALUE 0.0
J 2
(-250 -425);
DISPLAY 0.617021 (-250 -425);
PAINT SKYBLUE (-250 -425);
FORCEPROP 1 LAST PART_NUMBER G21497-005
J 0
(-325 -375);
DISPLAY 0.617021 (-325 -375);
PAINT BLUE (-325 -375);
FORCEPROP 1 LAST TOLERANCE 5%
J 0
(-225 -425);
DISPLAY 0.617021 (-225 -425);
PAINT SKYBLUE (-225 -425);
FORCEPROP 1 LAST MATERIAL CHIP
J 0
(-225 -475);
DISPLAY 0.617021 (-225 -475);
PAINT SKYBLUE (-225 -475);
FORCEPROP 1 LAST PACK_TYPE 0402
J 0
(-125 -475);
DISPLAY 0.617021 (-125 -475);
PAINT SKYBLUE (-125 -475);
FORCEPROP 1 LAST LOCATION RT36
J 0
(-275 -300);
DISPLAY 0.617021 (-275 -300);
PAINT AQUA (-275 -300);
FORCEPROP 2 LAST ROOM BMC_DEBUG_HEADER
J 0
(-275 -175);
DISPLAY 1.021277 (-275 -175);
PAINT ORANGE (-275 -175);
DISPLAY INVISIBLE (-275 -175);
FORCEPROP 2 LAST BOM_COST DEBUG
J 0
(-275 -125);
DISPLAY 1.021277 (-275 -125);
PAINT ORANGE (-275 -125);
DISPLAY INVISIBLE (-275 -125);
FORCEPROP 1 LAST PATH I127
J 0
(-275 -175);
DISPLAY 0.978723 (-275 -175);
PAINT WHITE (-275 -175);
DISPLAY INVISIBLE (-275 -175);
FORCEPROP 2 LAST CDS_LIB mstr_discrete
J 0
(-225 -325);
PAINT MONO (-225 -325);
DISPLAY INVISIBLE (-225 -325);
FORCEPROP 1 LASTPIN (-325 -325) $PN 1
J 0
(-313 -313);
DISPLAY 0.787234 (-313 -313);
PAINT ORANGE (-313 -313);
DISPLAY INVISIBLE (-313 -313);
FORCEPROP 1 LASTPIN (-125 -325) $PN 2
J 0
(-163 -313);
DISPLAY 0.787234 (-163 -313);
PAINT ORANGE (-163 -313);
DISPLAY INVISIBLE (-163 -313);
FORCEADD CAP..1
R 2
(-1150 -475);
FORCEPROP 1 LASTPIN (-1150 -575) $PN 2
J 2
(-1160 -595);
DISPLAY 0.617021 (-1160 -595);
PAINT ORANGE (-1160 -595);
FORCEPROP 1 LAST TOLERANCE 10%
J 2
(-1200 -525);
DISPLAY 0.617021 (-1200 -525);
PAINT SKYBLUE (-1200 -525);
FORCEPROP 1 LAST VOLTAGE 16V
J 2
(-1200 -475);
DISPLAY 0.617021 (-1200 -475);
PAINT SKYBLUE (-1200 -475);
FORCEPROP 1 LAST VALUE 0.220UF
J 2
(-1200 -425);
DISPLAY 0.617021 (-1200 -425);
PAINT SKYBLUE (-1200 -425);
FORCEPROP 1 LAST LOCATION C7G38
J 2
(-1200 -375);
DISPLAY 0.617021 (-1200 -375);
PAINT AQUA (-1200 -375);
FORCEPROP 1 LASTPIN (-1150 -375) $PN 1
J 2
(-1160 -395);
DISPLAY 0.617021 (-1160 -395);
PAINT ORANGE (-1160 -395);
FORCEPROP 1 LAST PART_NUMBER A36096-104
J 2
(-1200 -625);
DISPLAY 0.617021 (-1200 -625);
PAINT BLUE (-1200 -625);
FORCEPROP 1 LAST PACK_TYPE 0402
J 2
(-1200 -675);
DISPLAY 0.617021 (-1200 -675);
PAINT SKYBLUE (-1200 -675);
FORCEPROP 1 LAST MATERIAL X7R
J 2
(-1200 -575);
DISPLAY 0.617021 (-1200 -575);
PAINT SKYBLUE (-1200 -575);
FORCEPROP 1 LAST PATH I128
J 2
(-1200 -325);
DISPLAY 0.978723 (-1200 -325);
PAINT WHITE (-1200 -325);
DISPLAY INVISIBLE (-1200 -325);
FORCEPROP 2 LAST CDS_LIB mstr_discrete
J 0
(-1150 -475);
PAINT ORANGE (-1150 -475);
DISPLAY INVISIBLE (-1150 -475);
FORCEPROP 2 LAST SEC_TYPE 0402
J 0
(-1200 -275);
DISPLAY 1.021277 (-1200 -275);
PAINT ORANGE (-1200 -275);
DISPLAY INVISIBLE (-1200 -275);
FORCEPROP 0 LAST SPOF TRUE
J 0
(-1200 -275);
DISPLAY 1.021277 (-1200 -275);
PAINT ORANGE (-1200 -275);
DISPLAY INVISIBLE (-1200 -275);
FORCEPROP 2 LAST SEC 1
J 0
(-1200 -275);
DISPLAY 0.680851 (-1200 -275);
PAINT MONO (-1200 -275);
DISPLAY INVISIBLE (-1200 -275);
FORCEPROP 2 LAST CDS_LOCATION C7G38
J 2
(-1200 -375);
DISPLAY 0.617021 (-1200 -375);
PAINT AQUA (-1200 -375);
DISPLAY INVISIBLE (-1200 -375);
FORCEPROP 2 LAST ROOM VDDQ_ABC_PWR_VR
J 0
(-1200 -325);
DISPLAY 1.361702 (-1200 -325);
PAINT ORANGE (-1200 -325);
DISPLAY INVISIBLE (-1200 -325);
FORCEPROP 0 LAST CDS_SEC 1
J 0
(-1200 -325);
PAINT MONO (-1200 -325);
DISPLAY INVISIBLE (-1200 -325);
FORCEADD GND..1
(2100 1575);
FORCEPROP 3 LASTPIN (2100 1625) SIG_NAME GND\g
J 0
(2110 1635);
DISPLAY 0.659574 (2110 1635);
PAINT MONO (2110 1635);
DISPLAY INVISIBLE (2110 1635);
FORCEPROP 2 LAST ROOM VDDQ_ABC_PWR_VR
J 0
(1550 1650);
DISPLAY 1.936170 (1550 1650);
PAINT ORANGE (1550 1650);
DISPLAY INVISIBLE (1550 1650);
FORCEPROP 2 LAST BOM_COST PROC_VRD_VCCIN_CPU0
J 0
(1725 1650);
DISPLAY 1.446809 (1725 1650);
PAINT MONO (1725 1650);
DISPLAY INVISIBLE (1725 1650);
FORCEPROP 1 LAST BODY_TYPE PLUMBING
J 0
(2055 1532);
DISPLAY 0.340426 (2055 1532);
PAINT GREEN (2055 1532);
DISPLAY INVISIBLE (2055 1532);
FORCEPROP 1 LAST SIZE 1B
J 0
(2175 1525);
DISPLAY 1.723404 (2175 1525);
PAINT GREEN (2175 1525);
DISPLAY INVISIBLE (2175 1525);
FORCEPROP 1 LAST PATH I19
J 0
(2175 1575);
DISPLAY 0.893617 (2175 1575);
PAINT AQUA (2175 1575);
DISPLAY INVISIBLE (2175 1575);
FORCEPROP 2 LAST CDS_LIB mstr_symbols
J 0
(2100 1575);
DISPLAY 1.936170 (2100 1575);
PAINT ORANGE (2100 1575);
DISPLAY INVISIBLE (2100 1575);
FORCEPROP 1 LAST VOLTAGE 0
J 0
(2100 1575);
PAINT SKYBLUE (2100 1575);
DISPLAY INVISIBLE (2100 1575);
FORCEPROP 1 LAST HDL_POWER GND
J 0
(2100 1725);
DISPLAY 1.723404 (2100 1725);
PAINT GREEN (2100 1725);
DISPLAY INVISIBLE (2100 1725);
FORCEADD OFFPAGE..2
(3275 2800);
FORCEPROP 2 LAST $XR0 215 
J 0
(3464 2800);
DISPLAY 0.638298 (3464 2800);
PAINT MONO (3464 2800);
FORCEPROP 2 LAST ROOM VDDQ_ABC_PWR_VR
J 0
(2875 2875);
DISPLAY 1.936170 (2875 2875);
PAINT ORANGE (2875 2875);
DISPLAY INVISIBLE (2875 2875);
FORCEPROP 1 LAST COMMENT_BODY TRUE
J 0
(3230 2705);
DISPLAY 1.723404 (3230 2705);
PAINT GREEN (3230 2705);
DISPLAY INVISIBLE (3230 2705);
FORCEPROP 2 LAST CDS_LIB mstr_standard
J 0
(3275 2800);
DISPLAY 1.936170 (3275 2800);
PAINT ORANGE (3275 2800);
DISPLAY INVISIBLE (3275 2800);
FORCEPROP 2 LAST PATH I3
J 0
(3465 2850);
DISPLAY 1.021277 (3465 2850);
PAINT ORANGE (3465 2850);
DISPLAY INVISIBLE (3465 2850);
FORCEPROP 2 LAST BOM_COST PROC_VRD_VCCIN_CPU0
J 0
(3475 2850);
DISPLAY 1.446809 (3475 2850);
PAINT MONO (3475 2850);
DISPLAY INVISIBLE (3475 2850);
FORCEPROP 1 LAST OFFPAGE TRUE
J 0
(3600 2675);
DISPLAY 1.723404 (3600 2675);
PAINT GREEN (3600 2675);
DISPLAY INVISIBLE (3600 2675);
FORCEADD OFFPAGE..1
(-1875 2150);
FORCEPROP 2 LAST $XR0 215 
J 0
(-2127 2150);
DISPLAY 0.638298 (-2127 2150);
PAINT MONO (-2127 2150);
FORCEPROP 2 LASTPIN (-1825 2150) SIG_NAME VR_PVDDQ_ABC_PWM1
J 0
(-1810 2160);
DISPLAY 0.617021 (-1810 2160);
PAINT ORANGE (-1810 2160);
FORCEPROP 2 LAST BOM_COST PROC_VRD_VCCIN_CPU0
J 0
(-2125 2200);
DISPLAY 1.446809 (-2125 2200);
PAINT MONO (-2125 2200);
DISPLAY INVISIBLE (-2125 2200);
FORCEPROP 2 LAST PATH I33
J 0
(-2155 2200);
DISPLAY 1.021277 (-2155 2200);
PAINT ORANGE (-2155 2200);
DISPLAY INVISIBLE (-2155 2200);
FORCEPROP 2 LAST ROOM VDDQ_ABC_PWR_VR
J 0
(-2275 2225);
DISPLAY 1.936170 (-2275 2225);
PAINT ORANGE (-2275 2225);
DISPLAY INVISIBLE (-2275 2225);
FORCEPROP 1 LAST OFFPAGE TRUE
J 0
(-1550 2025);
DISPLAY 1.680851 (-1550 2025);
PAINT GREEN (-1550 2025);
DISPLAY INVISIBLE (-1550 2025);
FORCEPROP 2 LAST CDS_LIB mstr_standard
J 0
(-1875 2150);
DISPLAY 1.936170 (-1875 2150);
PAINT ORANGE (-1875 2150);
DISPLAY INVISIBLE (-1875 2150);
FORCEPROP 1 LAST COMMENT_BODY TRUE
J 0
(-1750 2050);
DISPLAY 1.680851 (-1750 2050);
PAINT GREEN (-1750 2050);
DISPLAY INVISIBLE (-1750 2050);
FORCEADD GND..1
(-2675 2075);
FORCEPROP 3 LASTPIN (-2675 2125) SIG_NAME GND\g
J 0
(-2665 2135);
DISPLAY 0.659574 (-2665 2135);
PAINT MONO (-2665 2135);
DISPLAY INVISIBLE (-2665 2135);
FORCEPROP 1 LAST BODY_TYPE PLUMBING
J 0
(-2720 2032);
DISPLAY 0.340426 (-2720 2032);
PAINT GREEN (-2720 2032);
DISPLAY INVISIBLE (-2720 2032);
FORCEPROP 1 LAST SIZE 1B
J 0
(-2600 2025);
DISPLAY 1.723404 (-2600 2025);
PAINT GREEN (-2600 2025);
DISPLAY INVISIBLE (-2600 2025);
FORCEPROP 2 LAST ROOM VDDQ_ABC_PWR_VR
J 0
(-3225 2150);
DISPLAY 1.936170 (-3225 2150);
PAINT ORANGE (-3225 2150);
DISPLAY INVISIBLE (-3225 2150);
FORCEPROP 2 LAST BOM_COST PROC_VRD_VCCIN_CPU0
J 0
(-3050 2150);
DISPLAY 1.446809 (-3050 2150);
PAINT MONO (-3050 2150);
DISPLAY INVISIBLE (-3050 2150);
FORCEPROP 1 LAST HDL_POWER GND
J 0
(-2675 2225);
DISPLAY 1.723404 (-2675 2225);
PAINT GREEN (-2675 2225);
DISPLAY INVISIBLE (-2675 2225);
FORCEPROP 1 LAST PATH I35
J 0
(-2600 2075);
DISPLAY 0.893617 (-2600 2075);
PAINT AQUA (-2600 2075);
DISPLAY INVISIBLE (-2600 2075);
FORCEPROP 1 LAST VOLTAGE 0
J 0
(-2675 2075);
PAINT SKYBLUE (-2675 2075);
DISPLAY INVISIBLE (-2675 2075);
FORCEPROP 2 LAST CDS_LIB mstr_symbols
J 0
(-2675 2075);
DISPLAY 1.936170 (-2675 2075);
PAINT ORANGE (-2675 2075);
DISPLAY INVISIBLE (-2675 2075);
FORCEADD OFFPAGE..2
(3250 3125);
FORCEPROP 2 LAST $XR0 215 
J 0
(3439 3125);
DISPLAY 0.638298 (3439 3125);
PAINT MONO (3439 3125);
FORCEPROP 2 LAST ROOM VDDQ_ABC_PWR_VR
J 0
(2850 3200);
DISPLAY 1.936170 (2850 3200);
PAINT ORANGE (2850 3200);
DISPLAY INVISIBLE (2850 3200);
FORCEPROP 1 LAST OFFPAGE TRUE
J 0
(3575 3000);
DISPLAY 1.723404 (3575 3000);
PAINT GREEN (3575 3000);
DISPLAY INVISIBLE (3575 3000);
FORCEPROP 1 LAST COMMENT_BODY TRUE
J 0
(3205 3030);
DISPLAY 1.723404 (3205 3030);
PAINT GREEN (3205 3030);
DISPLAY INVISIBLE (3205 3030);
FORCEPROP 2 LAST CDS_LIB mstr_standard
J 2
(3250 3125);
DISPLAY 1.936170 (3250 3125);
PAINT ORANGE (3250 3125);
DISPLAY INVISIBLE (3250 3125);
FORCEPROP 2 LAST PATH I4
J 0
(3440 3175);
DISPLAY 1.021277 (3440 3175);
PAINT ORANGE (3440 3175);
DISPLAY INVISIBLE (3440 3175);
FORCEPROP 2 LAST BOM_COST PROC_VRD_VCCIN_CPU0
J 0
(3450 3175);
DISPLAY 1.446809 (3450 3175);
PAINT MONO (3450 3175);
DISPLAY INVISIBLE (3450 3175);
FORCEADD CAP..1
R 2
(-1025 1875);
FORCEPROP 1 LASTPIN (-1025 1975) $PN 1
J 2
(-1035 1955);
DISPLAY 0.617021 (-1035 1955);
PAINT ORANGE (-1035 1955);
FORCEPROP 1 LASTPIN (-1025 1775) $PN 2
J 2
(-1035 1755);
DISPLAY 0.617021 (-1035 1755);
PAINT ORANGE (-1035 1755);
FORCEPROP 1 LAST LOCATION C7G31
J 2
(-1075 1975);
DISPLAY 0.617021 (-1075 1975);
PAINT AQUA (-1075 1975);
FORCEPROP 1 LAST PART_NUMBER A36096-104
J 2
(-1075 1725);
DISPLAY 0.617021 (-1075 1725);
PAINT BLUE (-1075 1725);
FORCEPROP 1 LAST VALUE 0.220UF
J 2
(-1075 1925);
DISPLAY 0.617021 (-1075 1925);
PAINT SKYBLUE (-1075 1925);
FORCEPROP 1 LAST TOLERANCE 10%
J 2
(-1075 1825);
DISPLAY 0.617021 (-1075 1825);
PAINT SKYBLUE (-1075 1825);
FORCEPROP 1 LAST VOLTAGE 16V
J 2
(-1075 1875);
DISPLAY 0.617021 (-1075 1875);
PAINT SKYBLUE (-1075 1875);
FORCEPROP 1 LAST MATERIAL X7R
J 2
(-1075 1775);
DISPLAY 0.617021 (-1075 1775);
PAINT SKYBLUE (-1075 1775);
FORCEPROP 1 LAST PACK_TYPE 0402
J 2
(-1075 1675);
DISPLAY 0.617021 (-1075 1675);
PAINT SKYBLUE (-1075 1675);
FORCEPROP 2 LAST CDS_LIB mstr_discrete
J 0
(-1025 1875);
PAINT ORANGE (-1025 1875);
DISPLAY INVISIBLE (-1025 1875);
FORCEPROP 2 LAST SEC_TYPE 0402
J 0
(-1075 2075);
DISPLAY 1.021277 (-1075 2075);
PAINT ORANGE (-1075 2075);
DISPLAY INVISIBLE (-1075 2075);
FORCEPROP 0 LAST SPOF TRUE
J 0
(-1075 2075);
DISPLAY 1.021277 (-1075 2075);
PAINT ORANGE (-1075 2075);
DISPLAY INVISIBLE (-1075 2075);
FORCEPROP 2 LAST SEC 1
J 0
(-1075 2075);
DISPLAY 0.680851 (-1075 2075);
PAINT MONO (-1075 2075);
DISPLAY INVISIBLE (-1075 2075);
FORCEPROP 2 LAST CDS_LOCATION C7G31
J 2
(-1075 1975);
DISPLAY 0.617021 (-1075 1975);
PAINT AQUA (-1075 1975);
DISPLAY INVISIBLE (-1075 1975);
FORCEPROP 1 LAST PATH I44
J 2
(-1075 2025);
DISPLAY 0.978723 (-1075 2025);
PAINT WHITE (-1075 2025);
DISPLAY INVISIBLE (-1075 2025);
FORCEPROP 2 LAST ROOM VDDQ_ABC_PWR_VR
J 0
(-1100 2025);
DISPLAY 1.361702 (-1100 2025);
PAINT ORANGE (-1100 2025);
DISPLAY INVISIBLE (-1100 2025);
FORCEADD CAP..1
(-2675 2525);
FORCEPROP 1 LASTPIN (-2675 2425) $PN 2
J 0
(-2665 2405);
DISPLAY 0.617021 (-2665 2405);
PAINT ORANGE (-2665 2405);
FORCEPROP 1 LASTPIN (-2675 2625) $PN 1
J 0
(-2665 2605);
DISPLAY 0.617021 (-2665 2605);
PAINT ORANGE (-2665 2605);
FORCEPROP 1 LAST MATERIAL X6S
J 0
(-2625 2425);
DISPLAY 0.617021 (-2625 2425);
PAINT SKYBLUE (-2625 2425);
FORCEPROP 1 LAST VOLTAGE 16V
J 0
(-2625 2525);
DISPLAY 0.617021 (-2625 2525);
PAINT SKYBLUE (-2625 2525);
FORCEPROP 1 LAST PACK_TYPE 0805
J 0
(-2625 2325);
DISPLAY 0.617021 (-2625 2325);
PAINT SKYBLUE (-2625 2325);
FORCEPROP 1 LAST TOLERANCE 10%
J 0
(-2625 2475);
DISPLAY 0.617021 (-2625 2475);
PAINT SKYBLUE (-2625 2475);
FORCEPROP 1 LAST VALUE 10UF
J 0
(-2625 2575);
DISPLAY 0.617021 (-2625 2575);
PAINT SKYBLUE (-2625 2575);
FORCEPROP 1 LAST PART_NUMBER C95333-007
J 0
(-2625 2375);
DISPLAY 0.617021 (-2625 2375);
PAINT BLUE (-2625 2375);
FORCEPROP 1 LAST LOCATION C3U2
J 0
(-2625 2625);
DISPLAY 0.617021 (-2625 2625);
PAINT AQUA (-2625 2625);
FORCEPROP 2 LAST CDS_LIB mstr_discrete
J 0
(-2675 2525);
PAINT ORANGE (-2675 2525);
DISPLAY INVISIBLE (-2675 2525);
FORCEPROP 2 LAST CDS_LOCATION C3U2
J 0
(-2625 2625);
DISPLAY 0.617021 (-2625 2625);
PAINT AQUA (-2625 2625);
DISPLAY INVISIBLE (-2625 2625);
FORCEPROP 2 LAST ROOM VDDQ_ABC_PWR_VR
J 0
(-2625 2675);
DISPLAY 1.361702 (-2625 2675);
PAINT ORANGE (-2625 2675);
DISPLAY INVISIBLE (-2625 2675);
FORCEPROP 1 LAST PATH I45
J 0
(-2625 2675);
DISPLAY 1.319149 (-2625 2675);
PAINT WHITE (-2625 2675);
DISPLAY INVISIBLE (-2625 2675);
FORCEPROP 2 LAST SEC 1
J 0
(-2625 2750);
DISPLAY 0.680851 (-2625 2750);
PAINT MONO (-2625 2750);
DISPLAY INVISIBLE (-2625 2750);
FORCEPROP 2 LAST SEC_TYPE 0805
J 0
(-2625 2750);
DISPLAY 1.021277 (-2625 2750);
PAINT ORANGE (-2625 2750);
DISPLAY INVISIBLE (-2625 2750);
FORCEADD CAP..1
(-2425 2525);
FORCEPROP 1 LASTPIN (-2425 2425) $PN 2
J 0
(-2415 2405);
DISPLAY 0.617021 (-2415 2405);
PAINT ORANGE (-2415 2405);
FORCEPROP 1 LAST VOLTAGE 16V
J 0
(-2375 2525);
DISPLAY 0.617021 (-2375 2525);
PAINT SKYBLUE (-2375 2525);
FORCEPROP 1 LAST TOLERANCE 10%
J 0
(-2375 2475);
DISPLAY 0.617021 (-2375 2475);
PAINT SKYBLUE (-2375 2475);
FORCEPROP 1 LAST PACK_TYPE 0805
J 0
(-2375 2325);
DISPLAY 0.617021 (-2375 2325);
PAINT SKYBLUE (-2375 2325);
FORCEPROP 1 LAST PART_NUMBER C95333-007
J 0
(-2375 2375);
DISPLAY 0.617021 (-2375 2375);
PAINT BLUE (-2375 2375);
FORCEPROP 1 LAST MATERIAL X6S
J 0
(-2375 2425);
DISPLAY 0.617021 (-2375 2425);
PAINT SKYBLUE (-2375 2425);
FORCEPROP 1 LASTPIN (-2425 2625) $PN 1
J 0
(-2415 2605);
DISPLAY 0.617021 (-2415 2605);
PAINT ORANGE (-2415 2605);
FORCEPROP 1 LAST VALUE 10UF
J 0
(-2375 2575);
DISPLAY 0.617021 (-2375 2575);
PAINT SKYBLUE (-2375 2575);
FORCEPROP 1 LAST LOCATION C3U3
J 0
(-2375 2625);
DISPLAY 0.617021 (-2375 2625);
PAINT AQUA (-2375 2625);
FORCEPROP 2 LAST CDS_LIB mstr_discrete
J 0
(-2425 2525);
PAINT ORANGE (-2425 2525);
DISPLAY INVISIBLE (-2425 2525);
FORCEPROP 1 LAST PATH I46
J 0
(-2375 2675);
DISPLAY 1.319149 (-2375 2675);
PAINT WHITE (-2375 2675);
DISPLAY INVISIBLE (-2375 2675);
FORCEPROP 2 LAST ROOM VDDQ_ABC_PWR_VR
J 0
(-2375 2675);
DISPLAY 1.361702 (-2375 2675);
PAINT ORANGE (-2375 2675);
DISPLAY INVISIBLE (-2375 2675);
FORCEPROP 2 LAST SEC_TYPE 0805
J 0
(-2375 2750);
DISPLAY 1.021277 (-2375 2750);
PAINT ORANGE (-2375 2750);
DISPLAY INVISIBLE (-2375 2750);
FORCEPROP 2 LAST SEC 1
J 0
(-2375 2750);
DISPLAY 0.680851 (-2375 2750);
PAINT MONO (-2375 2750);
DISPLAY INVISIBLE (-2375 2750);
FORCEPROP 2 LAST CDS_LOCATION C3U3
J 0
(-2375 2625);
DISPLAY 0.617021 (-2375 2625);
PAINT AQUA (-2375 2625);
DISPLAY INVISIBLE (-2375 2625);
FORCEADD CAP..1
(-2150 2550);
FORCEPROP 1 LASTPIN (-2150 2450) $PN 2
J 0
(-2140 2430);
DISPLAY 0.617021 (-2140 2430);
PAINT ORANGE (-2140 2430);
FORCEPROP 1 LASTPIN (-2150 2650) $PN 1
J 0
(-2140 2630);
DISPLAY 0.617021 (-2140 2630);
PAINT ORANGE (-2140 2630);
FORCEPROP 1 LAST MATERIAL X6S
J 0
(-2100 2450);
DISPLAY 0.617021 (-2100 2450);
PAINT SKYBLUE (-2100 2450);
FORCEPROP 1 LAST VOLTAGE 16V
J 0
(-2100 2550);
DISPLAY 0.617021 (-2100 2550);
PAINT SKYBLUE (-2100 2550);
FORCEPROP 1 LAST PACK_TYPE 0805
J 0
(-2100 2350);
DISPLAY 0.617021 (-2100 2350);
PAINT SKYBLUE (-2100 2350);
FORCEPROP 1 LAST TOLERANCE 10%
J 0
(-2100 2500);
DISPLAY 0.617021 (-2100 2500);
PAINT SKYBLUE (-2100 2500);
FORCEPROP 1 LAST VALUE 10UF
J 0
(-2100 2600);
DISPLAY 0.617021 (-2100 2600);
PAINT SKYBLUE (-2100 2600);
FORCEPROP 1 LAST PART_NUMBER C95333-007
J 0
(-2100 2400);
DISPLAY 0.617021 (-2100 2400);
PAINT BLUE (-2100 2400);
FORCEPROP 1 LAST LOCATION C3U4
J 0
(-2100 2650);
DISPLAY 0.617021 (-2100 2650);
PAINT AQUA (-2100 2650);
FORCEPROP 2 LAST CDS_LIB mstr_discrete
J 0
(-2150 2550);
PAINT ORANGE (-2150 2550);
DISPLAY INVISIBLE (-2150 2550);
FORCEPROP 2 LAST SEC 1
J 0
(-2100 2775);
DISPLAY 0.680851 (-2100 2775);
PAINT MONO (-2100 2775);
DISPLAY INVISIBLE (-2100 2775);
FORCEPROP 2 LAST CDS_LOCATION C3U4
J 0
(-2100 2650);
DISPLAY 0.617021 (-2100 2650);
PAINT AQUA (-2100 2650);
DISPLAY INVISIBLE (-2100 2650);
FORCEPROP 1 LAST PATH I47
J 0
(-2100 2700);
DISPLAY 1.319149 (-2100 2700);
PAINT WHITE (-2100 2700);
DISPLAY INVISIBLE (-2100 2700);
FORCEPROP 2 LAST ROOM VDDQ_ABC_PWR_VR
J 0
(-2100 2700);
DISPLAY 1.361702 (-2100 2700);
PAINT ORANGE (-2100 2700);
DISPLAY INVISIBLE (-2100 2700);
FORCEPROP 2 LAST SEC_TYPE 0805
J 0
(-2100 2775);
DISPLAY 1.021277 (-2100 2775);
PAINT ORANGE (-2100 2775);
DISPLAY INVISIBLE (-2100 2775);
FORCEADD CAP..1
(-1900 2475);
FORCEPROP 1 LASTPIN (-1900 2375) $PN 2
J 0
(-1890 2355);
DISPLAY 0.617021 (-1890 2355);
PAINT ORANGE (-1890 2355);
FORCEPROP 1 LAST MATERIAL X6S
J 0
(-1850 2375);
DISPLAY 0.617021 (-1850 2375);
PAINT SKYBLUE (-1850 2375);
FORCEPROP 1 LAST VOLTAGE 16V
J 0
(-1850 2475);
DISPLAY 0.617021 (-1850 2475);
PAINT SKYBLUE (-1850 2475);
FORCEPROP 1 LAST PACK_TYPE 0402
J 0
(-1850 2275);
DISPLAY 0.617021 (-1850 2275);
PAINT SKYBLUE (-1850 2275);
FORCEPROP 1 LAST TOLERANCE 10%
J 0
(-1850 2425);
DISPLAY 0.617021 (-1850 2425);
PAINT SKYBLUE (-1850 2425);
FORCEPROP 1 LAST VALUE 1.0UF
J 0
(-1850 2525);
DISPLAY 0.617021 (-1850 2525);
PAINT SKYBLUE (-1850 2525);
FORCEPROP 1 LAST PART_NUMBER D97712-011
J 0
(-1850 2325);
DISPLAY 0.617021 (-1850 2325);
PAINT BLUE (-1850 2325);
FORCEPROP 1 LASTPIN (-1900 2575) $PN 1
J 0
(-1890 2555);
DISPLAY 0.617021 (-1890 2555);
PAINT ORANGE (-1890 2555);
FORCEPROP 1 LAST LOCATION C7G37
J 0
(-1850 2575);
DISPLAY 0.617021 (-1850 2575);
PAINT AQUA (-1850 2575);
FORCEPROP 2 LAST CDS_LIB mstr_discrete
J 0
(-1900 2475);
PAINT ORANGE (-1900 2475);
DISPLAY INVISIBLE (-1900 2475);
FORCEPROP 2 LAST SEC_TYPE 0402
J 0
(-1850 2700);
DISPLAY 1.021277 (-1850 2700);
PAINT ORANGE (-1850 2700);
DISPLAY INVISIBLE (-1850 2700);
FORCEPROP 2 LAST SEC 1
J 0
(-1850 2700);
DISPLAY 0.680851 (-1850 2700);
PAINT MONO (-1850 2700);
DISPLAY INVISIBLE (-1850 2700);
FORCEPROP 2 LAST CDS_LOCATION C7G37
J 0
(-1850 2575);
DISPLAY 0.617021 (-1850 2575);
PAINT AQUA (-1850 2575);
DISPLAY INVISIBLE (-1850 2575);
FORCEPROP 1 LAST PATH I48
J 0
(-1850 2625);
DISPLAY 1.319149 (-1850 2625);
PAINT WHITE (-1850 2625);
DISPLAY INVISIBLE (-1850 2625);
FORCEPROP 2 LAST ROOM VDDQ_ABC_PWR_VR
J 0
(-1850 2625);
DISPLAY 1.361702 (-1850 2625);
PAINT ORANGE (-1850 2625);
DISPLAY INVISIBLE (-1850 2625);
FORCEADD CAP..1
(-1400 2475);
FORCEPROP 1 LASTPIN (-1400 2375) $PN 2
J 0
(-1390 2355);
DISPLAY 0.617021 (-1390 2355);
PAINT ORANGE (-1390 2355);
FORCEPROP 1 LAST PART_NUMBER D97712-011
J 0
(-1350 2325);
DISPLAY 0.617021 (-1350 2325);
PAINT BLUE (-1350 2325);
FORCEPROP 1 LAST VALUE 1.0UF
J 0
(-1350 2525);
DISPLAY 0.617021 (-1350 2525);
PAINT SKYBLUE (-1350 2525);
FORCEPROP 1 LAST TOLERANCE 10%
J 0
(-1350 2425);
DISPLAY 0.617021 (-1350 2425);
PAINT SKYBLUE (-1350 2425);
FORCEPROP 1 LAST PACK_TYPE 0402
J 0
(-1350 2275);
DISPLAY 0.617021 (-1350 2275);
PAINT SKYBLUE (-1350 2275);
FORCEPROP 1 LAST VOLTAGE 16V
J 0
(-1350 2475);
DISPLAY 0.617021 (-1350 2475);
PAINT SKYBLUE (-1350 2475);
FORCEPROP 1 LAST MATERIAL X6S
J 0
(-1350 2375);
DISPLAY 0.617021 (-1350 2375);
PAINT SKYBLUE (-1350 2375);
FORCEPROP 1 LASTPIN (-1400 2575) $PN 1
J 0
(-1390 2555);
DISPLAY 0.617021 (-1390 2555);
PAINT ORANGE (-1390 2555);
FORCEPROP 1 LAST LOCATION C7G33
J 0
(-1350 2575);
DISPLAY 0.617021 (-1350 2575);
PAINT AQUA (-1350 2575);
FORCEPROP 2 LAST CDS_LIB mstr_discrete
J 0
(-1400 2475);
PAINT ORANGE (-1400 2475);
DISPLAY INVISIBLE (-1400 2475);
FORCEPROP 2 LAST SEC_TYPE 0402
J 0
(-1350 2700);
DISPLAY 1.021277 (-1350 2700);
PAINT ORANGE (-1350 2700);
DISPLAY INVISIBLE (-1350 2700);
FORCEPROP 2 LAST SEC 1
J 0
(-1350 2700);
DISPLAY 0.680851 (-1350 2700);
PAINT MONO (-1350 2700);
DISPLAY INVISIBLE (-1350 2700);
FORCEPROP 2 LAST CDS_LOCATION C7G33
J 0
(-1350 2575);
DISPLAY 0.617021 (-1350 2575);
PAINT AQUA (-1350 2575);
DISPLAY INVISIBLE (-1350 2575);
FORCEPROP 1 LAST PATH I50
J 0
(-1350 2625);
DISPLAY 1.319149 (-1350 2625);
PAINT WHITE (-1350 2625);
DISPLAY INVISIBLE (-1350 2625);
FORCEPROP 2 LAST ROOM VDDQ_ABC_PWR_VR
J 0
(-1350 2625);
DISPLAY 1.361702 (-1350 2625);
PAINT ORANGE (-1350 2625);
DISPLAY INVISIBLE (-1350 2625);
FORCEADD CAP_A..1
(-1650 2475);
FORCEPROP 1 LASTPIN (-1650 2375) $PN 2
J 0
(-1640 2355);
DISPLAY 0.617021 (-1640 2355);
PAINT ORANGE (-1640 2355);
FORCEPROP 1 LASTPIN (-1650 2575) $PN 1
J 0
(-1640 2555);
DISPLAY 0.617021 (-1640 2555);
PAINT ORANGE (-1640 2555);
FORCEPROP 1 LAST MATERIAL X7R
J 0
(-1600 2375);
DISPLAY 0.617021 (-1600 2375);
PAINT SKYBLUE (-1600 2375);
FORCEPROP 1 LAST VOLTAGE 16V
J 0
(-1600 2475);
DISPLAY 0.617021 (-1600 2475);
PAINT SKYBLUE (-1600 2475);
FORCEPROP 1 LAST PACK_TYPE 0402V
J 0
(-1600 2275);
DISPLAY 0.617021 (-1600 2275);
PAINT SKYBLUE (-1600 2275);
FORCEPROP 1 LAST TOLERANCE 10%
J 0
(-1600 2425);
DISPLAY 0.617021 (-1600 2425);
PAINT SKYBLUE (-1600 2425);
FORCEPROP 1 LAST VALUE 0.1UF
J 0
(-1600 2525);
DISPLAY 0.617021 (-1600 2525);
PAINT SKYBLUE (-1600 2525);
FORCEPROP 1 LAST PART_NUMBER A36096-030
J 0
(-1600 2325);
DISPLAY 0.617021 (-1600 2325);
PAINT BLUE (-1600 2325);
FORCEPROP 1 LAST LOCATION C7G29
J 0
(-1600 2575);
DISPLAY 0.617021 (-1600 2575);
PAINT AQUA (-1600 2575);
FORCEPROP 2 LAST CDS_LIB dev_discrete
J 0
(-1650 2475);
PAINT ORANGE (-1650 2475);
DISPLAY INVISIBLE (-1650 2475);
FORCEPROP 2 LAST SEC 1
J 0
(-1600 2700);
DISPLAY 0.680851 (-1600 2700);
PAINT MONO (-1600 2700);
DISPLAY INVISIBLE (-1600 2700);
FORCEPROP 2 LAST SEC_TYPE 0402V
J 0
(-1600 2700);
DISPLAY 1.021277 (-1600 2700);
PAINT ORANGE (-1600 2700);
DISPLAY INVISIBLE (-1600 2700);
FORCEPROP 2 LAST CDS_SEC 1
J 0
(-1600 2625);
PAINT ORANGE (-1600 2625);
DISPLAY INVISIBLE (-1600 2625);
FORCEPROP 2 LAST CDS_LOCATION C7G29
J 0
(-1600 2575);
DISPLAY 0.617021 (-1600 2575);
PAINT AQUA (-1600 2575);
DISPLAY INVISIBLE (-1600 2575);
FORCEPROP 2 LAST ROOM VDDQ_ABC_PWR_VR
J 0
(-1600 2625);
DISPLAY 1.361702 (-1600 2625);
PAINT ORANGE (-1600 2625);
DISPLAY INVISIBLE (-1600 2625);
FORCEPROP 1 LAST PATH I51
J 0
(-1600 2625);
DISPLAY 0.978723 (-1600 2625);
PAINT WHITE (-1600 2625);
DISPLAY INVISIBLE (-1600 2625);
FORCEADD RES..1
(-1175 3050);
FORCEPROP 1 LAST PART_NUMBER G21796-090
J 0
(-1300 2975);
DISPLAY 0.617021 (-1300 2975);
PAINT BLUE (-1300 2975);
FORCEPROP 1 LAST WATTAGE 1/16W
J 2
(-1150 2875);
DISPLAY 0.617021 (-1150 2875);
PAINT SKYBLUE (-1150 2875);
FORCEPROP 1 LAST VALUE 1.0
J 2
(-1275 2925);
DISPLAY 0.617021 (-1275 2925);
PAINT SKYBLUE (-1275 2925);
FORCEPROP 1 LAST TOLERANCE 1%
J 0
(-1225 2925);
DISPLAY 0.617021 (-1225 2925);
PAINT SKYBLUE (-1225 2925);
FORCEPROP 1 LASTPIN (-1275 3050) $PN 1
J 0
(-1263 3062);
DISPLAY 0.617021 (-1263 3062);
PAINT ORANGE (-1263 3062);
FORCEPROP 1 LASTPIN (-1075 3050) $PN 2
J 0
(-1113 3062);
DISPLAY 0.617021 (-1113 3062);
PAINT ORANGE (-1113 3062);
FORCEPROP 1 LAST LOCATION R3U6
J 0
(-1225 3100);
DISPLAY 0.617021 (-1225 3100);
PAINT AQUA (-1225 3100);
FORCEPROP 1 LAST MATERIAL CHIP
J 0
(-1100 2875);
DISPLAY 0.617021 (-1100 2875);
PAINT SKYBLUE (-1100 2875);
FORCEPROP 1 LAST PACK_TYPE 0402
J 0
(-1125 2925);
DISPLAY 0.617021 (-1125 2925);
PAINT SKYBLUE (-1125 2925);
FORCEPROP 2 LAST CDS_LIB mstr_discrete
J 0
(-1175 3050);
PAINT ORANGE (-1175 3050);
DISPLAY INVISIBLE (-1175 3050);
FORCEPROP 2 LAST ROOM VDDQ_ABC_PWR_VR
J 0
(-1225 3150);
DISPLAY 1.361702 (-1225 3150);
PAINT ORANGE (-1225 3150);
DISPLAY INVISIBLE (-1225 3150);
FORCEPROP 1 LAST PATH I52
J 0
(-1225 3200);
DISPLAY 1.319149 (-1225 3200);
PAINT WHITE (-1225 3200);
DISPLAY INVISIBLE (-1225 3200);
FORCEPROP 2 LAST CDS_LOCATION R3U6
J 0
(-1225 3100);
DISPLAY 0.617021 (-1225 3100);
PAINT AQUA (-1225 3100);
DISPLAY INVISIBLE (-1225 3100);
FORCEPROP 2 LAST SEC 1
J 0
(-1225 3275);
DISPLAY 0.680851 (-1225 3275);
PAINT MONO (-1225 3275);
DISPLAY INVISIBLE (-1225 3275);
FORCEPROP 2 LAST SEC_TYPE 0402
J 0
(-1225 3275);
DISPLAY 1.021277 (-1225 3275);
PAINT ORANGE (-1225 3275);
DISPLAY INVISIBLE (-1225 3275);
FORCEADD CAP_A..1
R 2
(-675 2500);
FORCEPROP 1 LAST TOLERANCE 10%
J 2
(-725 2450);
DISPLAY 0.617021 (-725 2450);
PAINT SKYBLUE (-725 2450);
FORCEPROP 1 LAST PART_NUMBER D97712-004
J 2
(-725 2350);
DISPLAY 0.617021 (-725 2350);
PAINT BLUE (-725 2350);
FORCEPROP 1 LAST PACK_TYPE 0402V
J 2
(-725 2300);
DISPLAY 0.617021 (-725 2300);
PAINT SKYBLUE (-725 2300);
FORCEPROP 1 LAST VOLTAGE 6.3V
J 2
(-725 2500);
DISPLAY 0.617021 (-725 2500);
PAINT SKYBLUE (-725 2500);
FORCEPROP 1 LASTPIN (-675 2400) $PN 2
J 2
(-685 2380);
DISPLAY 0.617021 (-685 2380);
PAINT ORANGE (-685 2380);
FORCEPROP 1 LAST VALUE 1.0UF
J 2
(-725 2550);
DISPLAY 0.617021 (-725 2550);
PAINT SKYBLUE (-725 2550);
FORCEPROP 1 LASTPIN (-675 2600) $PN 1
J 2
(-685 2580);
DISPLAY 0.617021 (-685 2580);
PAINT ORANGE (-685 2580);
FORCEPROP 1 LAST LOCATION C7G35
J 2
(-725 2600);
DISPLAY 0.617021 (-725 2600);
PAINT AQUA (-725 2600);
FORCEPROP 1 LAST MATERIAL X6S
J 2
(-725 2400);
DISPLAY 0.617021 (-725 2400);
PAINT SKYBLUE (-725 2400);
FORCEPROP 2 LAST CDS_LIB dev_discrete
J 0
(-675 2500);
PAINT ORANGE (-675 2500);
DISPLAY INVISIBLE (-675 2500);
FORCEPROP 2 LAST CDS_LOCATION C7G35
J 2
(-725 2600);
DISPLAY 0.617021 (-725 2600);
PAINT AQUA (-725 2600);
DISPLAY INVISIBLE (-725 2600);
FORCEPROP 2 LAST CDS_SEC 1
J 0
(-725 2650);
PAINT ORANGE (-725 2650);
DISPLAY INVISIBLE (-725 2650);
FORCEPROP 2 LAST SEC_TYPE 0402V
J 0
(-725 2725);
DISPLAY 1.021277 (-725 2725);
PAINT ORANGE (-725 2725);
DISPLAY INVISIBLE (-725 2725);
FORCEPROP 2 LAST SEC 1
J 0
(-725 2725);
DISPLAY 0.680851 (-725 2725);
PAINT MONO (-725 2725);
DISPLAY INVISIBLE (-725 2725);
FORCEPROP 1 LAST PATH I53
J 2
(-725 2650);
DISPLAY 0.978723 (-725 2650);
PAINT WHITE (-725 2650);
DISPLAY INVISIBLE (-725 2650);
FORCEPROP 2 LAST ROOM VDDQ_ABC_PWR_VR
J 0
(-725 2650);
DISPLAY 1.361702 (-725 2650);
PAINT ORANGE (-725 2650);
DISPLAY INVISIBLE (-725 2650);
FORCEADD CAP..1
(-500 2525);
FORCEPROP 1 LASTPIN (-500 2425) $PN 2
J 0
(-490 2405);
DISPLAY 0.617021 (-490 2405);
PAINT ORANGE (-490 2405);
FORCEPROP 1 LASTPIN (-500 2625) $PN 1
J 0
(-490 2605);
DISPLAY 0.617021 (-490 2605);
PAINT ORANGE (-490 2605);
FORCEPROP 1 LAST LOCATION C7G34
J 0
(-450 2625);
DISPLAY 0.617021 (-450 2625);
PAINT AQUA (-450 2625);
FORCEPROP 1 LAST PART_NUMBER A36096-155
J 0
(-450 2375);
DISPLAY 0.617021 (-450 2375);
PAINT BLUE (-450 2375);
FORCEPROP 1 LAST MATERIAL X7R
J 0
(-450 2425);
DISPLAY 0.617021 (-450 2425);
PAINT SKYBLUE (-450 2425);
FORCEPROP 1 LAST TOLERANCE 10%
J 0
(-450 2475);
DISPLAY 0.617021 (-450 2475);
PAINT SKYBLUE (-450 2475);
FORCEPROP 1 LAST VOLTAGE 16V
J 0
(-450 2525);
DISPLAY 0.617021 (-450 2525);
PAINT SKYBLUE (-450 2525);
FORCEPROP 1 LAST VALUE 0.22UF
J 0
(-450 2575);
DISPLAY 0.617021 (-450 2575);
PAINT SKYBLUE (-450 2575);
FORCEPROP 1 LAST PACK_TYPE 0402
J 0
(-450 2325);
DISPLAY 0.617021 (-450 2325);
PAINT SKYBLUE (-450 2325);
FORCEPROP 2 LAST CDS_LIB mstr_discrete
J 0
(-500 2525);
PAINT ORANGE (-500 2525);
DISPLAY INVISIBLE (-500 2525);
FORCEPROP 2 LAST SEC_TYPE 0402
J 0
(-450 2750);
DISPLAY 1.021277 (-450 2750);
PAINT ORANGE (-450 2750);
DISPLAY INVISIBLE (-450 2750);
FORCEPROP 2 LAST SEC 1
J 0
(-450 2750);
DISPLAY 0.680851 (-450 2750);
PAINT MONO (-450 2750);
DISPLAY INVISIBLE (-450 2750);
FORCEPROP 2 LAST CDS_LOCATION C7G34
J 0
(-450 2625);
DISPLAY 0.617021 (-450 2625);
PAINT AQUA (-450 2625);
DISPLAY INVISIBLE (-450 2625);
FORCEPROP 1 LAST PATH I54
J 0
(-450 2675);
DISPLAY 1.319149 (-450 2675);
PAINT WHITE (-450 2675);
DISPLAY INVISIBLE (-450 2675);
FORCEPROP 2 LAST ROOM VDDQ_ABC_PWR_VR
J 0
(-450 2675);
DISPLAY 1.361702 (-450 2675);
PAINT ORANGE (-450 2675);
DISPLAY INVISIBLE (-450 2675);
FORCEADD OFFPAGE..2
(3275 2450);
FORCEPROP 2 LAST $XR1 215 
J 0
(3584 2450);
DISPLAY 0.638298 (3584 2450);
PAINT MONO (3584 2450);
FORCEPROP 2 LAST $XR0 216 
J 0
(3464 2450);
DISPLAY 0.638298 (3464 2450);
PAINT MONO (3464 2450);
FORCEPROP 2 LAST BOM_COST PROC_VRD_VCCIN_CPU0
J 0
(3475 2500);
DISPLAY 1.446809 (3475 2500);
PAINT MONO (3475 2500);
DISPLAY INVISIBLE (3475 2500);
FORCEPROP 1 LAST OFFPAGE TRUE
J 0
(3600 2325);
DISPLAY 1.723404 (3600 2325);
PAINT GREEN (3600 2325);
DISPLAY INVISIBLE (3600 2325);
FORCEPROP 2 LAST PATH I58
J 0
(3455 2525);
DISPLAY 1.361702 (3455 2525);
PAINT ORANGE (3455 2525);
DISPLAY INVISIBLE (3455 2525);
FORCEPROP 2 LAST CDS_LIB mstr_standard
J 0
(3275 2450);
PAINT ORANGE (3275 2450);
DISPLAY INVISIBLE (3275 2450);
FORCEPROP 1 LAST COMMENT_BODY TRUE
J 0
(3230 2355);
DISPLAY 1.723404 (3230 2355);
PAINT GREEN (3230 2355);
DISPLAY INVISIBLE (3230 2355);
FORCEPROP 2 LAST ROOM VDDQ_ABC_PWR_VR
J 0
(2875 2525);
DISPLAY 1.936170 (2875 2525);
PAINT ORANGE (2875 2525);
DISPLAY INVISIBLE (2875 2525);
FORCEADD CAP..1
(4000 1750);
FORCEPROP 1 LASTPIN (4000 1650) $PN 2
J 0
(4010 1630);
DISPLAY 0.617021 (4010 1630);
PAINT GREEN (4010 1630);
FORCEPROP 1 LASTPIN (4000 1850) $PN 1
J 0
(4010 1830);
DISPLAY 0.617021 (4010 1830);
PAINT GREEN (4010 1830);
FORCEPROP 1 LAST MATERIAL X6S
J 0
(4050 1650);
DISPLAY 0.617021 (4050 1650);
PAINT SKYBLUE (4050 1650);
FORCEPROP 1 LAST PACK_TYPE 0805LF
J 0
(4050 1550);
DISPLAY 0.617021 (4050 1550);
PAINT SKYBLUE (4050 1550);
FORCEPROP 1 LAST TOLERANCE 20%
J 0
(4050 1700);
DISPLAY 0.617021 (4050 1700);
PAINT SKYBLUE (4050 1700);
FORCEPROP 1 LAST VALUE 22UF
J 0
(4050 1800);
DISPLAY 0.617021 (4050 1800);
PAINT SKYBLUE (4050 1800);
FORCEPROP 1 LAST PART_NUMBER C95333-002
J 0
(4050 1600);
DISPLAY 0.617021 (4050 1600);
PAINT BLUE (4050 1600);
FORCEPROP 1 LAST LOCATION C6G3
J 0
(4050 1850);
DISPLAY 0.617021 (4050 1850);
PAINT AQUA (4050 1850);
FORCEPROP 2 LAST CDS_LIB mstr_discrete
J 0
(4000 1750);
DISPLAY 1.936170 (4000 1750);
PAINT ORANGE (4000 1750);
DISPLAY INVISIBLE (4000 1750);
FORCEPROP 1 LAST VOLTAGE 4V
J 0
(4050 1750);
DISPLAY 1.446809 (4050 1750);
PAINT SKYBLUE (4050 1750);
DISPLAY INVISIBLE (4050 1750);
FORCEPROP 2 LAST CDS_LOCATION C6G3
J 0
(4050 1850);
DISPLAY 0.617021 (4050 1850);
PAINT AQUA (4050 1850);
DISPLAY INVISIBLE (4050 1850);
FORCEPROP 2 LAST ROOM VDDQ_ABC_PWR_VR
J 0
(4050 1900);
DISPLAY 1.446809 (4050 1900);
PAINT MONO (4050 1900);
DISPLAY INVISIBLE (4050 1900);
FORCEPROP 1 LAST PATH I6
J 0
(4050 1900);
DISPLAY 0.978723 (4050 1900);
PAINT WHITE (4050 1900);
DISPLAY INVISIBLE (4050 1900);
FORCEPROP 2 LAST BOM_COST PROC_VRD_VCCIN_CPU0
J 0
(4050 1900);
DISPLAY 1.446809 (4050 1900);
PAINT MONO (4050 1900);
DISPLAY INVISIBLE (4050 1900);
FORCEPROP 2 LAST SEC 1
J 0
(4050 1950);
DISPLAY 1.936170 (4050 1950);
PAINT MONO (4050 1950);
DISPLAY INVISIBLE (4050 1950);
FORCEPROP 2 LAST SEC_TYPE 0805LF
J 0
(4050 1950);
DISPLAY 1.936170 (4050 1950);
PAINT MONO (4050 1950);
DISPLAY INVISIBLE (4050 1950);
FORCEADD OFFPAGE..2
(3125 750);
FORCEPROP 2 LAST $XR0 215 
J 0
(3314 750);
DISPLAY 0.638298 (3314 750);
PAINT MONO (3314 750);
FORCEPROP 2 LAST ROOM VDDQ_ABC_PWR_VR
J 0
(2725 825);
DISPLAY 1.936170 (2725 825);
PAINT ORANGE (2725 825);
DISPLAY INVISIBLE (2725 825);
FORCEPROP 1 LAST COMMENT_BODY TRUE
J 0
(3080 655);
DISPLAY 1.723404 (3080 655);
PAINT GREEN (3080 655);
DISPLAY INVISIBLE (3080 655);
FORCEPROP 2 LAST CDS_LIB mstr_standard
J 0
(3125 750);
PAINT ORANGE (3125 750);
DISPLAY INVISIBLE (3125 750);
FORCEPROP 2 LAST PATH I61
J 0
(3305 825);
DISPLAY 1.361702 (3305 825);
PAINT ORANGE (3305 825);
DISPLAY INVISIBLE (3305 825);
FORCEPROP 2 LAST BOM_COST PROC_VRD_VCCIN_CPU0
J 0
(3325 800);
DISPLAY 1.446809 (3325 800);
PAINT MONO (3325 800);
DISPLAY INVISIBLE (3325 800);
FORCEPROP 1 LAST OFFPAGE TRUE
J 0
(3450 625);
DISPLAY 1.723404 (3450 625);
PAINT GREEN (3450 625);
DISPLAY INVISIBLE (3450 625);
FORCEADD OFFPAGE..2
(3125 425);
FORCEPROP 2 LAST $XR0 215 
J 0
(3314 425);
DISPLAY 0.638298 (3314 425);
PAINT MONO (3314 425);
FORCEPROP 2 LAST ROOM VDDQ_ABC_PWR_VR
J 0
(2725 500);
DISPLAY 1.936170 (2725 500);
PAINT ORANGE (2725 500);
DISPLAY INVISIBLE (2725 500);
FORCEPROP 1 LAST COMMENT_BODY TRUE
J 0
(3080 330);
DISPLAY 1.723404 (3080 330);
PAINT GREEN (3080 330);
DISPLAY INVISIBLE (3080 330);
FORCEPROP 2 LAST CDS_LIB mstr_standard
J 0
(3125 425);
PAINT ORANGE (3125 425);
DISPLAY INVISIBLE (3125 425);
FORCEPROP 1 LAST OFFPAGE TRUE
J 0
(3450 300);
DISPLAY 1.723404 (3450 300);
PAINT GREEN (3450 300);
DISPLAY INVISIBLE (3450 300);
FORCEPROP 2 LAST PATH I62
J 0
(3305 500);
DISPLAY 1.361702 (3305 500);
PAINT ORANGE (3305 500);
DISPLAY INVISIBLE (3305 500);
FORCEPROP 2 LAST BOM_COST PROC_VRD_VCCIN_CPU0
J 0
(3325 475);
DISPLAY 1.446809 (3325 475);
PAINT MONO (3325 475);
DISPLAY INVISIBLE (3325 475);
FORCEADD OFFPAGE..2
(3275 50);
FORCEPROP 2 LAST $XR1 215 
J 0
(3584 50);
DISPLAY 0.638298 (3584 50);
PAINT MONO (3584 50);
FORCEPROP 2 LAST $XR0 216 
J 0
(3464 50);
DISPLAY 0.638298 (3464 50);
PAINT MONO (3464 50);
FORCEPROP 2 LAST BOM_COST PROC_VRD_VCCIN_CPU0
J 0
(3475 100);
DISPLAY 1.446809 (3475 100);
PAINT MONO (3475 100);
DISPLAY INVISIBLE (3475 100);
FORCEPROP 2 LAST ROOM VDDQ_ABC_PWR_VR
J 0
(2875 125);
DISPLAY 1.936170 (2875 125);
PAINT ORANGE (2875 125);
DISPLAY INVISIBLE (2875 125);
FORCEPROP 2 LAST PATH I63
J 0
(3455 125);
DISPLAY 1.361702 (3455 125);
PAINT ORANGE (3455 125);
DISPLAY INVISIBLE (3455 125);
FORCEPROP 1 LAST OFFPAGE TRUE
J 0
(3600 -75);
DISPLAY 1.723404 (3600 -75);
PAINT GREEN (3600 -75);
DISPLAY INVISIBLE (3600 -75);
FORCEPROP 1 LAST COMMENT_BODY TRUE
J 0
(3230 -45);
DISPLAY 1.723404 (3230 -45);
PAINT GREEN (3230 -45);
DISPLAY INVISIBLE (3230 -45);
FORCEPROP 2 LAST CDS_LIB mstr_standard
J 0
(3275 50);
PAINT ORANGE (3275 50);
DISPLAY INVISIBLE (3275 50);
FORCEADD PVDDQ_ABC..1
(4050 -325);
FORCEPROP 3 LASTPIN (4050 -375) SIG_NAME PVDDQ_ABC\g
J 0
(4060 -365);
DISPLAY 0.659574 (4060 -365);
PAINT MONO (4060 -365);
DISPLAY INVISIBLE (4060 -365);
FORCEPROP 1 LAST BODY_TYPE PLUMBING
J 0
(4005 -368);
DISPLAY 0.340426 (4005 -368);
PAINT GREEN (4005 -368);
DISPLAY INVISIBLE (4005 -368);
FORCEPROP 2 LAST CDS_LIB mstr_symbols
J 0
(4050 -325);
PAINT ORANGE (4050 -325);
DISPLAY INVISIBLE (4050 -325);
FORCEPROP 1 LAST VOLTAGE 1.2V
J 0
(4005 -368);
DISPLAY 0.340426 (4005 -368);
PAINT SKYBLUE (4005 -368);
DISPLAY INVISIBLE (4005 -368);
FORCEPROP 1 LAST HDL_POWER PVDDQ_ABC
J 1
(4050 -275);
DISPLAY 0.872340 (4050 -275);
PAINT GREEN (4050 -275);
DISPLAY INVISIBLE (4050 -275);
FORCEPROP 2 LAST ROOM VDDQ_ABC_PWR_VR
J 0
(4050 -225);
DISPLAY 1.936170 (4050 -225);
PAINT ORANGE (4050 -225);
DISPLAY INVISIBLE (4050 -225);
FORCEPROP 2 LAST BOM_COST PROC_SOCKET 
J 0
(4050 -225);
DISPLAY 1.446809 (4050 -225);
PAINT MONO (4050 -225);
DISPLAY INVISIBLE (4050 -225);
FORCEPROP 1 LAST PATH I64
J 0
(4100 -300);
DISPLAY 0.872340 (4100 -300);
PAINT AQUA (4100 -300);
DISPLAY INVISIBLE (4100 -300);
FORCEADD INDUCTOR..1
(3125 -425);
FORCEPROP 1 LAST VALUE 0.12UH
J 2
(3120 -535);
DISPLAY 0.617021 (3120 -535);
PAINT SKYBLUE (3120 -535);
FORCEPROP 1 LAST PACK_TYPE SM
J 0
(3290 -535);
DISPLAY 0.617021 (3290 -535);
PAINT SKYBLUE (3290 -535);
FORCEPROP 1 LASTPIN (3225 -425) $PN 2
J 2
(3235 -415);
DISPLAY 0.617021 (3235 -415);
PAINT WHITE (3235 -415);
FORCEPROP 1 LASTPIN (3025 -425) $PN 1
J 0
(3025 -415);
DISPLAY 0.617021 (3025 -415);
PAINT WHITE (3025 -415);
FORCEPROP 1 LAST MATERIAL IND
J 0
(3165 -535);
DISPLAY 0.617021 (3165 -535);
PAINT SKYBLUE (3165 -535);
FORCEPROP 1 LAST PART_NUMBER D92183-034
J 0
(3000 -475);
DISPLAY 0.617021 (3000 -475);
PAINT BLUE (3000 -475);
FORCEPROP 1 LAST LOCATION L7G2
J 0
(3025 -375);
DISPLAY 0.617021 (3025 -375);
PAINT AQUA (3025 -375);
FORCEPROP 2 LAST SEC 1
J 0
(3025 -200);
DISPLAY 0.680851 (3025 -200);
PAINT MONO (3025 -200);
DISPLAY INVISIBLE (3025 -200);
FORCEPROP 2 LAST SEC_TYPE SM
J 0
(3025 -200);
DISPLAY 1.021277 (3025 -200);
PAINT ORANGE (3025 -200);
DISPLAY INVISIBLE (3025 -200);
FORCEPROP 1 LAST PATH I65
J 0
(3025 -275);
DISPLAY 1.319149 (3025 -275);
PAINT ORANGE (3025 -275);
DISPLAY INVISIBLE (3025 -275);
FORCEPROP 2 LAST CDS_LOCATION L7G2
J 0
(3025 -375);
DISPLAY 0.617021 (3025 -375);
PAINT AQUA (3025 -375);
DISPLAY INVISIBLE (3025 -375);
FORCEPROP 2 LAST ROOM VDDQ_ABC_PWR_VR
J 0
(3025 -325);
DISPLAY 1.361702 (3025 -325);
PAINT ORANGE (3025 -325);
DISPLAY INVISIBLE (3025 -325);
FORCEPROP 2 LAST CDS_LIB mstr_discrete
J 0
(3125 -425);
PAINT ORANGE (3125 -425);
DISPLAY INVISIBLE (3125 -425);
FORCEADD CAP..1
(4050 -625);
FORCEPROP 1 LASTPIN (4050 -525) $PN 1
J 0
(4060 -545);
DISPLAY 0.617021 (4060 -545);
PAINT ORANGE (4060 -545);
FORCEPROP 1 LASTPIN (4050 -725) $PN 2
J 0
(4060 -745);
DISPLAY 0.617021 (4060 -745);
PAINT ORANGE (4060 -745);
FORCEPROP 1 LAST MATERIAL X6S
J 0
(4100 -725);
DISPLAY 0.617021 (4100 -725);
PAINT SKYBLUE (4100 -725);
FORCEPROP 1 LAST PACK_TYPE 0805LF
J 0
(4100 -825);
DISPLAY 0.617021 (4100 -825);
PAINT SKYBLUE (4100 -825);
FORCEPROP 1 LAST TOLERANCE 20%
J 0
(4100 -675);
DISPLAY 0.617021 (4100 -675);
PAINT SKYBLUE (4100 -675);
FORCEPROP 1 LAST VALUE 22UF
J 0
(4100 -575);
DISPLAY 0.617021 (4100 -575);
PAINT SKYBLUE (4100 -575);
FORCEPROP 1 LAST PART_NUMBER C95333-002
J 0
(4100 -775);
DISPLAY 0.617021 (4100 -775);
PAINT BLUE (4100 -775);
FORCEPROP 1 LAST LOCATION C7G27
J 0
(4100 -525);
DISPLAY 0.617021 (4100 -525);
PAINT AQUA (4100 -525);
FORCEPROP 2 LAST CDS_LIB mstr_discrete
J 0
(4050 -625);
PAINT ORANGE (4050 -625);
DISPLAY INVISIBLE (4050 -625);
FORCEPROP 1 LAST VOLTAGE 4V
J 0
(4100 -625);
DISPLAY 1.446809 (4100 -625);
PAINT SKYBLUE (4100 -625);
DISPLAY INVISIBLE (4100 -625);
FORCEPROP 2 LAST CDS_LOCATION C7G27
J 0
(4100 -525);
DISPLAY 0.617021 (4100 -525);
PAINT AQUA (4100 -525);
DISPLAY INVISIBLE (4100 -525);
FORCEPROP 2 LAST ROOM VDDQ_ABC_PWR_VR
J 0
(4100 -475);
DISPLAY 1.446809 (4100 -475);
PAINT MONO (4100 -475);
DISPLAY INVISIBLE (4100 -475);
FORCEPROP 1 LAST PATH I68
J 0
(4100 -475);
DISPLAY 1.319149 (4100 -475);
PAINT WHITE (4100 -475);
DISPLAY INVISIBLE (4100 -475);
FORCEPROP 2 LAST SEC 1
J 0
(4105 -400);
DISPLAY 0.680851 (4105 -400);
PAINT MONO (4105 -400);
DISPLAY INVISIBLE (4105 -400);
FORCEPROP 2 LAST SEC_TYPE 0805LF
J 0
(4100 -400);
DISPLAY 1.021277 (4100 -400);
PAINT ORANGE (4100 -400);
DISPLAY INVISIBLE (4100 -400);
FORCEPROP 2 LAST BOM_COST PROC_VRD_VCCIN_CPU0
J 0
(4100 -475);
DISPLAY 1.446809 (4100 -475);
PAINT MONO (4100 -475);
DISPLAY INVISIBLE (4100 -475);
FORCEADD GND..1
(4050 -850);
FORCEPROP 3 LASTPIN (4050 -800) SIG_NAME GND\g
J 0
(4060 -790);
DISPLAY 0.659574 (4060 -790);
PAINT MONO (4060 -790);
DISPLAY INVISIBLE (4060 -790);
FORCEPROP 2 LAST ROOM VDDQ_ABC_PWR_VR
J 0
(3500 -775);
DISPLAY 1.936170 (3500 -775);
PAINT ORANGE (3500 -775);
DISPLAY INVISIBLE (3500 -775);
FORCEPROP 2 LAST BOM_COST PROC_VRD_VCCIN_CPU0
J 0
(3675 -775);
DISPLAY 1.446809 (3675 -775);
PAINT MONO (3675 -775);
DISPLAY INVISIBLE (3675 -775);
FORCEPROP 1 LAST VOLTAGE 0
J 0
(4050 -850);
PAINT SKYBLUE (4050 -850);
DISPLAY INVISIBLE (4050 -850);
FORCEPROP 2 LAST CDS_LIB mstr_symbols
J 0
(4050 -850);
PAINT ORANGE (4050 -850);
DISPLAY INVISIBLE (4050 -850);
FORCEPROP 1 LAST BODY_TYPE PLUMBING
J 0
(4005 -893);
DISPLAY 0.340426 (4005 -893);
PAINT GREEN (4005 -893);
DISPLAY INVISIBLE (4005 -893);
FORCEPROP 1 LAST HDL_POWER GND
J 0
(4050 -700);
DISPLAY 1.723404 (4050 -700);
PAINT GREEN (4050 -700);
DISPLAY INVISIBLE (4050 -700);
FORCEPROP 1 LAST PATH I69
J 0
(4125 -850);
DISPLAY 1.170213 (4125 -850);
PAINT AQUA (4125 -850);
DISPLAY INVISIBLE (4125 -850);
FORCEPROP 1 LAST SIZE 1B
J 0
(4125 -900);
DISPLAY 1.723404 (4125 -900);
PAINT GREEN (4125 -900);
DISPLAY INVISIBLE (4125 -900);
FORCEADD GND..1
(4000 1525);
FORCEPROP 3 LASTPIN (4000 1575) SIG_NAME GND\g
J 0
(4010 1585);
DISPLAY 0.659574 (4010 1585);
PAINT MONO (4010 1585);
DISPLAY INVISIBLE (4010 1585);
FORCEPROP 2 LAST ROOM VDDQ_ABC_PWR_VR
J 0
(3450 1600);
DISPLAY 1.936170 (3450 1600);
PAINT ORANGE (3450 1600);
DISPLAY INVISIBLE (3450 1600);
FORCEPROP 1 LAST BODY_TYPE PLUMBING
J 0
(3955 1482);
DISPLAY 0.340426 (3955 1482);
PAINT GREEN (3955 1482);
DISPLAY INVISIBLE (3955 1482);
FORCEPROP 1 LAST PATH I7
J 0
(4075 1525);
DISPLAY 0.893617 (4075 1525);
PAINT AQUA (4075 1525);
DISPLAY INVISIBLE (4075 1525);
FORCEPROP 2 LAST CDS_LIB mstr_symbols
J 0
(4000 1525);
DISPLAY 1.936170 (4000 1525);
PAINT ORANGE (4000 1525);
DISPLAY INVISIBLE (4000 1525);
FORCEPROP 1 LAST SIZE 1B
J 0
(4075 1475);
DISPLAY 1.723404 (4075 1475);
PAINT GREEN (4075 1475);
DISPLAY INVISIBLE (4075 1475);
FORCEPROP 1 LAST VOLTAGE 0
J 0
(4000 1525);
PAINT SKYBLUE (4000 1525);
DISPLAY INVISIBLE (4000 1525);
FORCEPROP 2 LAST BOM_COST PROC_VRD_VCCIN_CPU0
J 0
(3625 1600);
DISPLAY 1.446809 (3625 1600);
PAINT MONO (3625 1600);
DISPLAY INVISIBLE (3625 1600);
FORCEPROP 1 LAST HDL_POWER GND
J 0
(4000 1675);
DISPLAY 1.723404 (4000 1675);
PAINT GREEN (4000 1675);
DISPLAY INVISIBLE (4000 1675);
FORCEADD GND..1
(2100 -875);
FORCEPROP 3 LASTPIN (2100 -825) SIG_NAME GND\g
J 0
(2110 -815);
DISPLAY 0.659574 (2110 -815);
PAINT MONO (2110 -815);
DISPLAY INVISIBLE (2110 -815);
FORCEPROP 2 LAST ROOM :VCCIN_CPU0_PWR_VR
J 0
(1550 -800);
DISPLAY 1.936170 (1550 -800);
PAINT ORANGE (1550 -800);
DISPLAY INVISIBLE (1550 -800);
FORCEPROP 2 LAST BOM_COST PROC_VRD_VCCIN_CPU0
J 0
(1725 -800);
DISPLAY 1.446809 (1725 -800);
PAINT MONO (1725 -800);
DISPLAY INVISIBLE (1725 -800);
FORCEPROP 1 LAST VOLTAGE 0
J 0
(2100 -875);
PAINT SKYBLUE (2100 -875);
DISPLAY INVISIBLE (2100 -875);
FORCEPROP 1 LAST SIZE 1B
J 0
(2175 -925);
DISPLAY 1.723404 (2175 -925);
PAINT GREEN (2175 -925);
DISPLAY INVISIBLE (2175 -925);
FORCEPROP 2 LAST CDS_LIB mstr_symbols
J 0
(2100 -875);
PAINT ORANGE (2100 -875);
DISPLAY INVISIBLE (2100 -875);
FORCEPROP 1 LAST BODY_TYPE PLUMBING
J 0
(2055 -918);
DISPLAY 0.340426 (2055 -918);
PAINT GREEN (2055 -918);
DISPLAY INVISIBLE (2055 -918);
FORCEPROP 1 LAST PATH I70
J 0
(2175 -875);
DISPLAY 1.170213 (2175 -875);
PAINT AQUA (2175 -875);
DISPLAY INVISIBLE (2175 -875);
FORCEPROP 1 LAST HDL_POWER GND
J 0
(2100 -725);
DISPLAY 1.723404 (2100 -725);
PAINT GREEN (2100 -725);
DISPLAY INVISIBLE (2100 -725);
FORCEADD CAP..1
(-450 150);
FORCEPROP 1 LAST VOLTAGE 16V
J 0
(-400 150);
DISPLAY 0.617021 (-400 150);
PAINT SKYBLUE (-400 150);
FORCEPROP 1 LAST VALUE 0.22UF
J 0
(-400 200);
DISPLAY 0.617021 (-400 200);
PAINT SKYBLUE (-400 200);
FORCEPROP 1 LASTPIN (-450 250) $PN 1
J 0
(-440 230);
DISPLAY 0.617021 (-440 230);
PAINT ORANGE (-440 230);
FORCEPROP 1 LAST TOLERANCE 10%
J 0
(-400 100);
DISPLAY 0.617021 (-400 100);
PAINT SKYBLUE (-400 100);
FORCEPROP 1 LAST MATERIAL X7R
J 0
(-400 50);
DISPLAY 0.617021 (-400 50);
PAINT SKYBLUE (-400 50);
FORCEPROP 1 LAST LOCATION C7G41
J 0
(-400 250);
DISPLAY 0.617021 (-400 250);
PAINT AQUA (-400 250);
FORCEPROP 1 LAST PACK_TYPE 0402
J 0
(-400 -50);
DISPLAY 0.617021 (-400 -50);
PAINT SKYBLUE (-400 -50);
FORCEPROP 1 LAST PART_NUMBER A36096-155
J 0
(-400 0);
DISPLAY 0.617021 (-400 0);
PAINT BLUE (-400 0);
FORCEPROP 1 LASTPIN (-450 50) $PN 2
J 0
(-440 30);
DISPLAY 0.617021 (-440 30);
PAINT ORANGE (-440 30);
FORCEPROP 2 LAST CDS_LIB mstr_discrete
J 0
(-450 150);
PAINT ORANGE (-450 150);
DISPLAY INVISIBLE (-450 150);
FORCEPROP 2 LAST CDS_LOCATION C7G41
J 0
(-400 250);
DISPLAY 0.617021 (-400 250);
PAINT AQUA (-400 250);
DISPLAY INVISIBLE (-400 250);
FORCEPROP 2 LAST SEC 1
J 0
(-400 375);
DISPLAY 0.680851 (-400 375);
PAINT MONO (-400 375);
DISPLAY INVISIBLE (-400 375);
FORCEPROP 2 LAST SEC_TYPE 0402
J 0
(-400 375);
DISPLAY 1.021277 (-400 375);
PAINT ORANGE (-400 375);
DISPLAY INVISIBLE (-400 375);
FORCEPROP 1 LAST PATH I72
J 0
(-400 300);
DISPLAY 1.319149 (-400 300);
PAINT WHITE (-400 300);
DISPLAY INVISIBLE (-400 300);
FORCEPROP 2 LAST ROOM VDDQ_ABC_PWR_VR
J 0
(-400 300);
DISPLAY 1.361702 (-400 300);
PAINT ORANGE (-400 300);
DISPLAY INVISIBLE (-400 300);
FORCEADD CAP_A..1
R 2
(-575 150);
FORCEPROP 1 LAST VALUE 1.0UF
J 2
(-625 200);
DISPLAY 0.617021 (-625 200);
PAINT SKYBLUE (-625 200);
FORCEPROP 1 LASTPIN (-575 50) $PN 2
J 2
(-585 30);
DISPLAY 0.617021 (-585 30);
PAINT ORANGE (-585 30);
FORCEPROP 1 LAST MATERIAL X6S
J 2
(-625 50);
DISPLAY 0.617021 (-625 50);
PAINT SKYBLUE (-625 50);
FORCEPROP 1 LAST TOLERANCE 10%
J 2
(-625 100);
DISPLAY 0.617021 (-625 100);
PAINT SKYBLUE (-625 100);
FORCEPROP 1 LAST VOLTAGE 6.3V
J 2
(-625 150);
DISPLAY 0.617021 (-625 150);
PAINT SKYBLUE (-625 150);
FORCEPROP 1 LASTPIN (-575 250) $PN 1
J 2
(-585 230);
DISPLAY 0.617021 (-585 230);
PAINT ORANGE (-585 230);
FORCEPROP 1 LAST LOCATION C7G42
J 2
(-625 250);
DISPLAY 0.617021 (-625 250);
PAINT AQUA (-625 250);
FORCEPROP 1 LAST PART_NUMBER D97712-004
J 2
(-625 0);
DISPLAY 0.617021 (-625 0);
PAINT BLUE (-625 0);
FORCEPROP 1 LAST PACK_TYPE 0402V
J 2
(-625 -50);
DISPLAY 0.617021 (-625 -50);
PAINT SKYBLUE (-625 -50);
FORCEPROP 2 LAST CDS_LIB dev_discrete
J 0
(-575 150);
PAINT ORANGE (-575 150);
DISPLAY INVISIBLE (-575 150);
FORCEPROP 2 LAST CDS_LOCATION C7G42
J 2
(-625 250);
DISPLAY 0.617021 (-625 250);
PAINT AQUA (-625 250);
DISPLAY INVISIBLE (-625 250);
FORCEPROP 2 LAST CDS_SEC 1
J 0
(-625 300);
PAINT ORANGE (-625 300);
DISPLAY INVISIBLE (-625 300);
FORCEPROP 2 LAST SEC_TYPE 0402V
J 0
(-625 375);
DISPLAY 1.021277 (-625 375);
PAINT ORANGE (-625 375);
DISPLAY INVISIBLE (-625 375);
FORCEPROP 2 LAST SEC 1
J 0
(-625 375);
DISPLAY 0.680851 (-625 375);
PAINT MONO (-625 375);
DISPLAY INVISIBLE (-625 375);
FORCEPROP 1 LAST PATH I73
J 2
(-625 300);
DISPLAY 0.978723 (-625 300);
PAINT WHITE (-625 300);
DISPLAY INVISIBLE (-625 300);
FORCEPROP 2 LAST ROOM VDDQ_ABC_PWR_VR
J 0
(-625 300);
DISPLAY 1.361702 (-625 300);
PAINT ORANGE (-625 300);
DISPLAY INVISIBLE (-625 300);
FORCEADD RES..1
(-1200 675);
FORCEPROP 1 LAST VALUE 1.0
J 2
(-1300 550);
DISPLAY 0.617021 (-1300 550);
PAINT SKYBLUE (-1300 550);
FORCEPROP 1 LAST PART_NUMBER G21796-090
J 0
(-1325 600);
DISPLAY 0.617021 (-1325 600);
PAINT BLUE (-1325 600);
FORCEPROP 1 LASTPIN (-1300 675) $PN 1
J 0
(-1288 687);
DISPLAY 0.617021 (-1288 687);
PAINT ORANGE (-1288 687);
FORCEPROP 1 LAST LOCATION R3U9
J 0
(-1250 725);
DISPLAY 0.617021 (-1250 725);
PAINT AQUA (-1250 725);
FORCEPROP 1 LAST MATERIAL CHIP
J 0
(-1125 500);
DISPLAY 0.617021 (-1125 500);
PAINT SKYBLUE (-1125 500);
FORCEPROP 1 LAST WATTAGE 1/16W
J 2
(-1175 500);
DISPLAY 0.617021 (-1175 500);
PAINT SKYBLUE (-1175 500);
FORCEPROP 1 LAST TOLERANCE 1%
J 0
(-1250 550);
DISPLAY 0.617021 (-1250 550);
PAINT SKYBLUE (-1250 550);
FORCEPROP 1 LAST PACK_TYPE 0402
J 0
(-1150 550);
DISPLAY 0.617021 (-1150 550);
PAINT SKYBLUE (-1150 550);
FORCEPROP 1 LASTPIN (-1100 675) $PN 2
J 0
(-1138 687);
DISPLAY 0.617021 (-1138 687);
PAINT ORANGE (-1138 687);
FORCEPROP 2 LAST CDS_LIB mstr_discrete
J 0
(-1200 675);
PAINT ORANGE (-1200 675);
DISPLAY INVISIBLE (-1200 675);
FORCEPROP 2 LAST CDS_LOCATION R3U9
J 0
(-1250 725);
DISPLAY 0.617021 (-1250 725);
PAINT AQUA (-1250 725);
DISPLAY INVISIBLE (-1250 725);
FORCEPROP 2 LAST ROOM VDDQ_ABC_PWR_VR
J 0
(-1250 775);
DISPLAY 1.361702 (-1250 775);
PAINT ORANGE (-1250 775);
DISPLAY INVISIBLE (-1250 775);
FORCEPROP 1 LAST PATH I76
J 0
(-1250 825);
DISPLAY 1.319149 (-1250 825);
PAINT WHITE (-1250 825);
DISPLAY INVISIBLE (-1250 825);
FORCEPROP 2 LAST SEC_TYPE 0402
J 0
(-1250 900);
DISPLAY 1.021277 (-1250 900);
PAINT ORANGE (-1250 900);
DISPLAY INVISIBLE (-1250 900);
FORCEPROP 2 LAST SEC 1
J 0
(-1250 900);
DISPLAY 0.680851 (-1250 900);
PAINT MONO (-1250 900);
DISPLAY INVISIBLE (-1250 900);
FORCEADD CAP..1
(-1450 125);
FORCEPROP 1 LAST PACK_TYPE 0402
J 0
(-1400 -75);
DISPLAY 0.617021 (-1400 -75);
PAINT SKYBLUE (-1400 -75);
FORCEPROP 1 LASTPIN (-1450 25) $PN 2
J 0
(-1440 5);
DISPLAY 0.617021 (-1440 5);
PAINT ORANGE (-1440 5);
FORCEPROP 1 LAST LOCATION C7G40
J 0
(-1400 225);
DISPLAY 0.617021 (-1400 225);
PAINT AQUA (-1400 225);
FORCEPROP 1 LAST VOLTAGE 16V
J 0
(-1400 125);
DISPLAY 0.617021 (-1400 125);
PAINT SKYBLUE (-1400 125);
FORCEPROP 1 LAST MATERIAL X6S
J 0
(-1400 25);
DISPLAY 0.617021 (-1400 25);
PAINT SKYBLUE (-1400 25);
FORCEPROP 1 LAST PART_NUMBER D97712-011
J 0
(-1400 -25);
DISPLAY 0.617021 (-1400 -25);
PAINT BLUE (-1400 -25);
FORCEPROP 1 LAST TOLERANCE 10%
J 0
(-1400 75);
DISPLAY 0.617021 (-1400 75);
PAINT SKYBLUE (-1400 75);
FORCEPROP 1 LASTPIN (-1450 225) $PN 1
J 0
(-1440 205);
DISPLAY 0.617021 (-1440 205);
PAINT ORANGE (-1440 205);
FORCEPROP 1 LAST VALUE 1.0UF
J 0
(-1400 175);
DISPLAY 0.617021 (-1400 175);
PAINT SKYBLUE (-1400 175);
FORCEPROP 2 LAST CDS_LIB mstr_discrete
J 0
(-1450 125);
PAINT ORANGE (-1450 125);
DISPLAY INVISIBLE (-1450 125);
FORCEPROP 2 LAST CDS_LOCATION C7G40
J 0
(-1400 225);
DISPLAY 0.617021 (-1400 225);
PAINT AQUA (-1400 225);
DISPLAY INVISIBLE (-1400 225);
FORCEPROP 2 LAST ROOM VDDQ_ABC_PWR_VR
J 0
(-1400 275);
DISPLAY 1.361702 (-1400 275);
PAINT ORANGE (-1400 275);
DISPLAY INVISIBLE (-1400 275);
FORCEPROP 1 LAST PATH I77
J 0
(-1400 275);
DISPLAY 1.319149 (-1400 275);
PAINT WHITE (-1400 275);
DISPLAY INVISIBLE (-1400 275);
FORCEPROP 2 LAST SEC 1
J 0
(-1400 350);
DISPLAY 0.680851 (-1400 350);
PAINT MONO (-1400 350);
DISPLAY INVISIBLE (-1400 350);
FORCEPROP 2 LAST SEC_TYPE 0402
J 0
(-1400 350);
DISPLAY 1.021277 (-1400 350);
PAINT ORANGE (-1400 350);
DISPLAY INVISIBLE (-1400 350);
FORCEADD CAP_A..1
(-1675 100);
FORCEPROP 1 LAST LOCATION C7G36
J 0
(-1625 200);
DISPLAY 0.617021 (-1625 200);
PAINT AQUA (-1625 200);
FORCEPROP 1 LAST PART_NUMBER A36096-030
J 0
(-1625 -50);
DISPLAY 0.617021 (-1625 -50);
PAINT BLUE (-1625 -50);
FORCEPROP 1 LAST PACK_TYPE 0402V
J 0
(-1625 -100);
DISPLAY 0.617021 (-1625 -100);
PAINT SKYBLUE (-1625 -100);
FORCEPROP 1 LASTPIN (-1675 0) $PN 2
J 0
(-1665 -20);
DISPLAY 0.617021 (-1665 -20);
PAINT ORANGE (-1665 -20);
FORCEPROP 1 LAST MATERIAL X7R
J 0
(-1625 0);
DISPLAY 0.617021 (-1625 0);
PAINT SKYBLUE (-1625 0);
FORCEPROP 1 LAST VOLTAGE 16V
J 0
(-1625 100);
DISPLAY 0.617021 (-1625 100);
PAINT SKYBLUE (-1625 100);
FORCEPROP 1 LASTPIN (-1675 200) $PN 1
J 0
(-1665 180);
DISPLAY 0.617021 (-1665 180);
PAINT ORANGE (-1665 180);
FORCEPROP 1 LAST VALUE 0.1UF
J 0
(-1625 150);
DISPLAY 0.617021 (-1625 150);
PAINT SKYBLUE (-1625 150);
FORCEPROP 1 LAST TOLERANCE 10%
J 0
(-1625 50);
DISPLAY 0.617021 (-1625 50);
PAINT SKYBLUE (-1625 50);
FORCEPROP 2 LAST CDS_LOCATION C7G36
J 0
(-1625 200);
DISPLAY 0.617021 (-1625 200);
PAINT AQUA (-1625 200);
DISPLAY INVISIBLE (-1625 200);
FORCEPROP 2 LAST CDS_LIB dev_discrete
J 0
(-1675 100);
PAINT ORANGE (-1675 100);
DISPLAY INVISIBLE (-1675 100);
FORCEPROP 1 LAST PATH I78
J 0
(-1625 250);
DISPLAY 0.978723 (-1625 250);
PAINT WHITE (-1625 250);
DISPLAY INVISIBLE (-1625 250);
FORCEPROP 2 LAST ROOM VDDQ_ABC_PWR_VR
J 0
(-1625 250);
DISPLAY 1.361702 (-1625 250);
PAINT ORANGE (-1625 250);
DISPLAY INVISIBLE (-1625 250);
FORCEPROP 2 LAST CDS_SEC 1
J 0
(-1625 250);
PAINT ORANGE (-1625 250);
DISPLAY INVISIBLE (-1625 250);
FORCEPROP 2 LAST SEC_TYPE 0402V
J 0
(-1625 325);
DISPLAY 1.021277 (-1625 325);
PAINT ORANGE (-1625 325);
DISPLAY INVISIBLE (-1625 325);
FORCEPROP 2 LAST SEC 1
J 0
(-1625 325);
DISPLAY 0.680851 (-1625 325);
PAINT MONO (-1625 325);
DISPLAY INVISIBLE (-1625 325);
FORCEADD CAP..1
(-1900 125);
FORCEPROP 1 LAST PACK_TYPE 0402
J 0
(-1850 -75);
DISPLAY 0.617021 (-1850 -75);
PAINT SKYBLUE (-1850 -75);
FORCEPROP 1 LAST PART_NUMBER D97712-011
J 0
(-1850 -25);
DISPLAY 0.617021 (-1850 -25);
PAINT BLUE (-1850 -25);
FORCEPROP 1 LASTPIN (-1900 25) $PN 2
J 0
(-1890 5);
DISPLAY 0.617021 (-1890 5);
PAINT ORANGE (-1890 5);
FORCEPROP 1 LASTPIN (-1900 225) $PN 1
J 0
(-1890 205);
DISPLAY 0.617021 (-1890 205);
PAINT ORANGE (-1890 205);
FORCEPROP 1 LAST MATERIAL X6S
J 0
(-1850 25);
DISPLAY 0.617021 (-1850 25);
PAINT SKYBLUE (-1850 25);
FORCEPROP 1 LAST VOLTAGE 16V
J 0
(-1850 125);
DISPLAY 0.617021 (-1850 125);
PAINT SKYBLUE (-1850 125);
FORCEPROP 1 LAST VALUE 1.0UF
J 0
(-1850 175);
DISPLAY 0.617021 (-1850 175);
PAINT SKYBLUE (-1850 175);
FORCEPROP 1 LAST LOCATION C7G30
J 0
(-1850 225);
DISPLAY 0.617021 (-1850 225);
PAINT AQUA (-1850 225);
FORCEPROP 1 LAST TOLERANCE 10%
J 0
(-1850 75);
DISPLAY 0.617021 (-1850 75);
PAINT SKYBLUE (-1850 75);
FORCEPROP 2 LAST CDS_LIB mstr_discrete
J 0
(-1900 125);
PAINT ORANGE (-1900 125);
DISPLAY INVISIBLE (-1900 125);
FORCEPROP 2 LAST CDS_LOCATION C7G30
J 0
(-1850 225);
DISPLAY 0.617021 (-1850 225);
PAINT AQUA (-1850 225);
DISPLAY INVISIBLE (-1850 225);
FORCEPROP 2 LAST SEC_TYPE 0402
J 0
(-1850 350);
DISPLAY 1.021277 (-1850 350);
PAINT ORANGE (-1850 350);
DISPLAY INVISIBLE (-1850 350);
FORCEPROP 2 LAST SEC 1
J 0
(-1850 350);
DISPLAY 0.680851 (-1850 350);
PAINT MONO (-1850 350);
DISPLAY INVISIBLE (-1850 350);
FORCEPROP 1 LAST PATH I79
J 0
(-1850 275);
DISPLAY 1.319149 (-1850 275);
PAINT WHITE (-1850 275);
DISPLAY INVISIBLE (-1850 275);
FORCEPROP 2 LAST ROOM VDDQ_ABC_PWR_VR
J 0
(-1850 275);
DISPLAY 1.361702 (-1850 275);
PAINT ORANGE (-1850 275);
DISPLAY INVISIBLE (-1850 275);
FORCEADD CAP..1
(-2125 100);
FORCEPROP 1 LAST PACK_TYPE 0805
J 0
(-2075 -100);
DISPLAY 0.617021 (-2075 -100);
PAINT SKYBLUE (-2075 -100);
FORCEPROP 1 LAST PART_NUMBER C95333-007
J 0
(-2075 -50);
DISPLAY 0.617021 (-2075 -50);
PAINT BLUE (-2075 -50);
FORCEPROP 1 LASTPIN (-2125 0) $PN 2
J 0
(-2115 -20);
DISPLAY 0.617021 (-2115 -20);
PAINT ORANGE (-2115 -20);
FORCEPROP 1 LAST MATERIAL X6S
J 0
(-2075 0);
DISPLAY 0.617021 (-2075 0);
PAINT SKYBLUE (-2075 0);
FORCEPROP 1 LASTPIN (-2125 200) $PN 1
J 0
(-2115 180);
DISPLAY 0.617021 (-2115 180);
PAINT ORANGE (-2115 180);
FORCEPROP 1 LAST VALUE 10UF
J 0
(-2075 150);
DISPLAY 0.617021 (-2075 150);
PAINT SKYBLUE (-2075 150);
FORCEPROP 1 LAST LOCATION C3U9
J 0
(-2075 200);
DISPLAY 0.617021 (-2075 200);
PAINT AQUA (-2075 200);
FORCEPROP 1 LAST VOLTAGE 16V
J 0
(-2075 100);
DISPLAY 0.617021 (-2075 100);
PAINT SKYBLUE (-2075 100);
FORCEPROP 1 LAST TOLERANCE 10%
J 0
(-2075 50);
DISPLAY 0.617021 (-2075 50);
PAINT SKYBLUE (-2075 50);
FORCEPROP 2 LAST CDS_LOCATION C3U9
J 0
(-2075 200);
DISPLAY 0.617021 (-2075 200);
PAINT AQUA (-2075 200);
DISPLAY INVISIBLE (-2075 200);
FORCEPROP 2 LAST CDS_LIB mstr_discrete
J 0
(-2125 100);
PAINT ORANGE (-2125 100);
DISPLAY INVISIBLE (-2125 100);
FORCEPROP 2 LAST ROOM VDDQ_ABC_PWR_VR
J 0
(-2075 250);
DISPLAY 1.361702 (-2075 250);
PAINT ORANGE (-2075 250);
DISPLAY INVISIBLE (-2075 250);
FORCEPROP 1 LAST PATH I80
J 0
(-2075 250);
DISPLAY 1.319149 (-2075 250);
PAINT WHITE (-2075 250);
DISPLAY INVISIBLE (-2075 250);
FORCEPROP 2 LAST SEC 1
J 0
(-2075 325);
DISPLAY 0.680851 (-2075 325);
PAINT MONO (-2075 325);
DISPLAY INVISIBLE (-2075 325);
FORCEPROP 2 LAST SEC_TYPE 0805
J 0
(-2075 325);
DISPLAY 1.021277 (-2075 325);
PAINT ORANGE (-2075 325);
DISPLAY INVISIBLE (-2075 325);
FORCEADD CAP..1
(-2350 125);
FORCEPROP 1 LAST PACK_TYPE 0805
J 0
(-2300 -75);
DISPLAY 0.617021 (-2300 -75);
PAINT SKYBLUE (-2300 -75);
FORCEPROP 1 LAST PART_NUMBER C95333-007
J 0
(-2300 -25);
DISPLAY 0.617021 (-2300 -25);
PAINT BLUE (-2300 -25);
FORCEPROP 1 LASTPIN (-2350 25) $PN 2
J 0
(-2340 5);
DISPLAY 0.617021 (-2340 5);
PAINT ORANGE (-2340 5);
FORCEPROP 1 LASTPIN (-2350 225) $PN 1
J 0
(-2340 205);
DISPLAY 0.617021 (-2340 205);
PAINT ORANGE (-2340 205);
FORCEPROP 1 LAST LOCATION C3U7
J 0
(-2300 225);
DISPLAY 0.617021 (-2300 225);
PAINT AQUA (-2300 225);
FORCEPROP 1 LAST VALUE 10UF
J 0
(-2300 175);
DISPLAY 0.617021 (-2300 175);
PAINT SKYBLUE (-2300 175);
FORCEPROP 1 LAST TOLERANCE 10%
J 0
(-2300 75);
DISPLAY 0.617021 (-2300 75);
PAINT SKYBLUE (-2300 75);
FORCEPROP 1 LAST VOLTAGE 16V
J 0
(-2300 125);
DISPLAY 0.617021 (-2300 125);
PAINT SKYBLUE (-2300 125);
FORCEPROP 1 LAST MATERIAL X6S
J 0
(-2300 25);
DISPLAY 0.617021 (-2300 25);
PAINT SKYBLUE (-2300 25);
FORCEPROP 2 LAST CDS_LIB mstr_discrete
J 0
(-2350 125);
PAINT ORANGE (-2350 125);
DISPLAY INVISIBLE (-2350 125);
FORCEPROP 2 LAST CDS_LOCATION C3U7
J 0
(-2300 225);
DISPLAY 0.617021 (-2300 225);
PAINT AQUA (-2300 225);
DISPLAY INVISIBLE (-2300 225);
FORCEPROP 2 LAST SEC_TYPE 0805
J 0
(-2300 350);
DISPLAY 1.021277 (-2300 350);
PAINT ORANGE (-2300 350);
DISPLAY INVISIBLE (-2300 350);
FORCEPROP 2 LAST SEC 1
J 0
(-2300 350);
DISPLAY 0.680851 (-2300 350);
PAINT MONO (-2300 350);
DISPLAY INVISIBLE (-2300 350);
FORCEPROP 1 LAST PATH I81
J 0
(-2300 275);
DISPLAY 1.319149 (-2300 275);
PAINT WHITE (-2300 275);
DISPLAY INVISIBLE (-2300 275);
FORCEPROP 2 LAST ROOM VDDQ_ABC_PWR_VR
J 0
(-2300 275);
DISPLAY 1.361702 (-2300 275);
PAINT ORANGE (-2300 275);
DISPLAY INVISIBLE (-2300 275);
FORCEADD OFFPAGE..1
(-1800 -225);
FORCEPROP 2 LAST $XR0 215 
J 0
(-2052 -225);
DISPLAY 0.638298 (-2052 -225);
PAINT MONO (-2052 -225);
FORCEPROP 2 LAST BOM_COST PROC_VRD_VCCIN_CPU0
J 0
(-2050 -175);
DISPLAY 1.446809 (-2050 -175);
PAINT MONO (-2050 -175);
DISPLAY INVISIBLE (-2050 -175);
FORCEPROP 2 LAST ROOM VDDQ_ABC_PWR_VR
J 0
(-2200 -150);
DISPLAY 1.936170 (-2200 -150);
PAINT ORANGE (-2200 -150);
DISPLAY INVISIBLE (-2200 -150);
FORCEPROP 2 LAST CDS_LIB mstr_standard
J 0
(-1800 -225);
PAINT ORANGE (-1800 -225);
DISPLAY INVISIBLE (-1800 -225);
FORCEPROP 2 LAST PATH I82
J 0
(-1745 -150);
DISPLAY 1.361702 (-1745 -150);
PAINT ORANGE (-1745 -150);
DISPLAY INVISIBLE (-1745 -150);
FORCEPROP 1 LAST COMMENT_BODY TRUE
J 0
(-1675 -325);
DISPLAY 1.680851 (-1675 -325);
PAINT GREEN (-1675 -325);
DISPLAY INVISIBLE (-1675 -325);
FORCEPROP 1 LAST OFFPAGE TRUE
J 0
(-1475 -350);
DISPLAY 1.680851 (-1475 -350);
PAINT GREEN (-1475 -350);
DISPLAY INVISIBLE (-1475 -350);
FORCEADD VCC_CORE..1
(-2600 675);
FORCEPROP 3 LASTPIN (-2600 625) SIG_NAME VR_FET_SW_P12V_STBY_PVDDQ_ABC\g
J 0
(-2590 635);
DISPLAY 0.659574 (-2590 635);
PAINT MONO (-2590 635);
DISPLAY INVISIBLE (-2590 635);
FORCEPROP 1 LAST HDL_POWER VR_FET_SW_P12V_STBY_PVDDQ_ABC
J 1
(-2525 725);
DISPLAY 0.617021 (-2525 725);
PAINT GREEN (-2525 725);
FORCEPROP 2 LAST CDS_LIB mstr_symbols
J 0
(-2600 675);
PAINT ORANGE (-2600 675);
DISPLAY INVISIBLE (-2600 675);
FORCEPROP 1 LAST PATH I83
J 0
(-2550 700);
DISPLAY 1.170213 (-2550 700);
PAINT AQUA (-2550 700);
DISPLAY INVISIBLE (-2550 700);
FORCEADD CAP..1
(-2600 100);
FORCEPROP 1 LAST PACK_TYPE 0805
J 0
(-2550 -100);
DISPLAY 0.617021 (-2550 -100);
PAINT SKYBLUE (-2550 -100);
FORCEPROP 1 LAST PART_NUMBER C95333-007
J 0
(-2550 -50);
DISPLAY 0.617021 (-2550 -50);
PAINT BLUE (-2550 -50);
FORCEPROP 1 LASTPIN (-2600 0) $PN 2
J 0
(-2590 -20);
DISPLAY 0.617021 (-2590 -20);
PAINT ORANGE (-2590 -20);
FORCEPROP 1 LAST MATERIAL X6S
J 0
(-2550 0);
DISPLAY 0.617021 (-2550 0);
PAINT SKYBLUE (-2550 0);
FORCEPROP 1 LASTPIN (-2600 200) $PN 1
J 0
(-2590 180);
DISPLAY 0.617021 (-2590 180);
PAINT ORANGE (-2590 180);
FORCEPROP 1 LAST VOLTAGE 16V
J 0
(-2550 100);
DISPLAY 0.617021 (-2550 100);
PAINT SKYBLUE (-2550 100);
FORCEPROP 1 LAST TOLERANCE 10%
J 0
(-2550 50);
DISPLAY 0.617021 (-2550 50);
PAINT SKYBLUE (-2550 50);
FORCEPROP 1 LAST VALUE 10UF
J 0
(-2550 150);
DISPLAY 0.617021 (-2550 150);
PAINT SKYBLUE (-2550 150);
FORCEPROP 1 LAST LOCATION C3U6
J 0
(-2550 200);
DISPLAY 0.617021 (-2550 200);
PAINT AQUA (-2550 200);
FORCEPROP 2 LAST CDS_LIB mstr_discrete
J 0
(-2600 100);
PAINT ORANGE (-2600 100);
DISPLAY INVISIBLE (-2600 100);
FORCEPROP 2 LAST CDS_LOCATION C3U6
J 0
(-2550 200);
DISPLAY 0.617021 (-2550 200);
PAINT AQUA (-2550 200);
DISPLAY INVISIBLE (-2550 200);
FORCEPROP 1 LAST PATH I84
J 0
(-2550 250);
DISPLAY 1.319149 (-2550 250);
PAINT WHITE (-2550 250);
DISPLAY INVISIBLE (-2550 250);
FORCEPROP 2 LAST ROOM VDDQ_ABC_PWR_VR
J 0
(-2550 250);
DISPLAY 1.361702 (-2550 250);
PAINT ORANGE (-2550 250);
DISPLAY INVISIBLE (-2550 250);
FORCEPROP 2 LAST SEC_TYPE 0805
J 0
(-2550 325);
DISPLAY 1.021277 (-2550 325);
PAINT ORANGE (-2550 325);
DISPLAY INVISIBLE (-2550 325);
FORCEPROP 2 LAST SEC 1
J 0
(-2550 325);
DISPLAY 0.680851 (-2550 325);
PAINT MONO (-2550 325);
DISPLAY INVISIBLE (-2550 325);
FORCEADD GND..1
(-2600 -275);
FORCEPROP 3 LASTPIN (-2600 -225) SIG_NAME GND\g
J 0
(-2590 -215);
DISPLAY 0.659574 (-2590 -215);
PAINT MONO (-2590 -215);
DISPLAY INVISIBLE (-2590 -215);
FORCEPROP 2 LAST ROOM VDDQ_ABC_PWR_VR
J 0
(-3150 -200);
DISPLAY 1.936170 (-3150 -200);
PAINT ORANGE (-3150 -200);
DISPLAY INVISIBLE (-3150 -200);
FORCEPROP 2 LAST BOM_COST PROC_VRD_VCCIN_CPU0
J 0
(-2975 -200);
DISPLAY 1.446809 (-2975 -200);
PAINT MONO (-2975 -200);
DISPLAY INVISIBLE (-2975 -200);
FORCEPROP 1 LAST BODY_TYPE PLUMBING
J 0
(-2645 -318);
DISPLAY 0.340426 (-2645 -318);
PAINT GREEN (-2645 -318);
DISPLAY INVISIBLE (-2645 -318);
FORCEPROP 1 LAST VOLTAGE 0
J 0
(-2600 -275);
PAINT SKYBLUE (-2600 -275);
DISPLAY INVISIBLE (-2600 -275);
FORCEPROP 2 LAST CDS_LIB mstr_symbols
J 0
(-2600 -275);
PAINT ORANGE (-2600 -275);
DISPLAY INVISIBLE (-2600 -275);
FORCEPROP 1 LAST HDL_POWER GND
J 0
(-2600 -125);
DISPLAY 1.723404 (-2600 -125);
PAINT GREEN (-2600 -125);
DISPLAY INVISIBLE (-2600 -125);
FORCEPROP 1 LAST SIZE 1B
J 0
(-2525 -325);
DISPLAY 1.723404 (-2525 -325);
PAINT GREEN (-2525 -325);
DISPLAY INVISIBLE (-2525 -325);
FORCEPROP 1 LAST PATH I85
J 0
(-2525 -275);
DISPLAY 1.170213 (-2525 -275);
PAINT AQUA (-2525 -275);
DISPLAY INVISIBLE (-2525 -275);
FORCEADD VCC_CORE..1
(-2675 2850);
FORCEPROP 3 LASTPIN (-2675 2800) SIG_NAME VR_FET_SW_P12V_STBY_PVDDQ_ABC\g
J 0
(-2665 2810);
DISPLAY 0.659574 (-2665 2810);
PAINT MONO (-2665 2810);
DISPLAY INVISIBLE (-2665 2810);
FORCEPROP 1 LAST HDL_POWER VR_FET_SW_P12V_STBY_PVDDQ_ABC
J 1
(-2575 2900);
DISPLAY 0.617021 (-2575 2900);
PAINT GREEN (-2575 2900);
FORCEPROP 1 LAST PATH I86
J 0
(-2625 2875);
DISPLAY 1.170213 (-2625 2875);
PAINT AQUA (-2625 2875);
DISPLAY INVISIBLE (-2625 2875);
FORCEPROP 2 LAST CDS_LIB mstr_symbols
J 0
(-2675 2850);
PAINT ORANGE (-2675 2850);
DISPLAY INVISIBLE (-2675 2850);
FORCEADD P5V_STBY..1
(0 3200);
FORCEPROP 3 LASTPIN (0 3150) SIG_NAME P5V_STBY\g
J 0
(10 3160);
DISPLAY 0.659574 (10 3160);
PAINT MONO (10 3160);
DISPLAY INVISIBLE (10 3160);
FORCEPROP 1 LAST HDL_POWER P5V_STBY
J 0
(-300 3075);
DISPLAY 0.872340 (-300 3075);
PAINT ORANGE (-300 3075);
DISPLAY INVISIBLE (-300 3075);
FORCEPROP 1 LAST BODY_TYPE PLUMBING
J 0
(-45 3157);
DISPLAY 0.340426 (-45 3157);
PAINT GREEN (-45 3157);
DISPLAY INVISIBLE (-45 3157);
FORCEPROP 1 LAST VOLTAGE 5.0V
J 0
(-45 3157);
DISPLAY 0.340426 (-45 3157);
PAINT SKYBLUE (-45 3157);
DISPLAY INVISIBLE (-45 3157);
FORCEPROP 2 LAST CDS_LIB mstr_symbols
J 0
(0 3200);
PAINT ORANGE (0 3200);
DISPLAY INVISIBLE (0 3200);
FORCEPROP 1 LAST PATH I87
J 0
(45 3202);
DISPLAY 0.340426 (45 3202);
PAINT GREEN (45 3202);
DISPLAY INVISIBLE (45 3202);
FORCEPROP 1 LAST SIZE 1B
J 0
(45 3222);
DISPLAY 0.340426 (45 3222);
PAINT GREEN (45 3222);
DISPLAY INVISIBLE (45 3222);
FORCEADD P5V_STBY..1
(150 850);
FORCEPROP 3 LASTPIN (150 800) SIG_NAME P5V_STBY\g
J 0
(160 810);
DISPLAY 0.659574 (160 810);
PAINT MONO (160 810);
DISPLAY INVISIBLE (160 810);
FORCEPROP 1 LAST HDL_POWER P5V_STBY
J 0
(-150 725);
DISPLAY 0.872340 (-150 725);
PAINT ORANGE (-150 725);
DISPLAY INVISIBLE (-150 725);
FORCEPROP 1 LAST VOLTAGE 5.0V
J 0
(105 807);
DISPLAY 0.340426 (105 807);
PAINT SKYBLUE (105 807);
DISPLAY INVISIBLE (105 807);
FORCEPROP 1 LAST SIZE 1B
J 0
(195 872);
DISPLAY 0.340426 (195 872);
PAINT GREEN (195 872);
DISPLAY INVISIBLE (195 872);
FORCEPROP 2 LAST CDS_LIB mstr_symbols
J 0
(150 850);
PAINT ORANGE (150 850);
DISPLAY INVISIBLE (150 850);
FORCEPROP 1 LAST BODY_TYPE PLUMBING
J 0
(105 807);
DISPLAY 0.340426 (105 807);
PAINT GREEN (105 807);
DISPLAY INVISIBLE (105 807);
FORCEPROP 1 LAST PATH I88
J 0
(195 852);
DISPLAY 0.340426 (195 852);
PAINT GREEN (195 852);
DISPLAY INVISIBLE (195 852);
FORCEADD DNS..2
(4230 2395);
PAINT RED (4230 2395);
FORCEPROP 1 LAST COMMENT_BODY TRUE
R 1
J 0
(4305 2170);
DISPLAY 0.872340 (4305 2170);
PAINT GREEN (4305 2170);
DISPLAY INVISIBLE (4305 2170);
FORCEPROP 2 LAST CDS_LIB mstr_misc
J 0
(4230 2395);
PAINT ORANGE (4230 2395);
DISPLAY INVISIBLE (4230 2395);
FORCEADD DNS..2
(4330 -5);
PAINT RED (4330 -5);
FORCEPROP 1 LAST COMMENT_BODY TRUE
R 1
J 0
(4405 -230);
DISPLAY 0.872340 (4405 -230);
PAINT GREEN (4405 -230);
DISPLAY INVISIBLE (4405 -230);
FORCEPROP 2 LAST CDS_LIB mstr_misc
J 0
(4330 -5);
PAINT ORANGE (4330 -5);
DISPLAY INVISIBLE (4330 -5);
FORCEADD INTEL_CORP_BPAGE..1
(4925 -1575);
FORCEPROP 1 LAST CDS_CON_LAST_MODIFIED Tue Dec 01 11:52:25 2015
J 0
(3500 -1250);
DISPLAY 1.936170 (3500 -1250);
PAINT GREEN (3500 -1250);
DISPLAY INVISIBLE (3500 -1250);
FORCEPROP 1 LAST CUSTOM_TXT_CDS <CURRENT_DESIGN_SHEET> OF <TOTAL_DESIGN_SHEETS>
J 0
(4425 -1550);
PAINT GREEN (4425 -1550);
FORCEPROP 1 LAST CUSTOM_TXT_CDS <CON_LAST_MODIFIED>
J 0
(3000 -1225);
PAINT GREEN (3000 -1225);
FORCEPROP 2 LAST CUSTOM_TXT_CDS <XR_PAGE_TITLE>
J 0
(-2965 3675);
DISPLAY 0.638298 (-2965 3675);
PAINT PINK (-2965 3675);
DISPLAY INVISIBLE (-2965 3675);
FORCEPROP 1 LAST SCH_DEPT BESD
J 1
(475 -1475);
DISPLAY 1.212766 (475 -1475);
PAINT YELLOW (475 -1475);
FORCEPROP 1 LAST SCH_NUMBER H4694802
J 0
(3625 -1425);
DISPLAY 1.212766 (3625 -1425);
PAINT YELLOW (3625 -1425);
FORCEPROP 1 LAST SCH_TITLE VDDQ ABC VR (2 OF 3)
J 0
(-3025 -1525);
DISPLAY 1.212766 (-3025 -1525);
PAINT ORANGE (-3025 -1525);
FORCEPROP 1 LAST SCH_ADDRESS1 2200 Mission College Blvd.
J 0
(950 -1450);
DISPLAY 0.617021 (950 -1450);
PAINT GREEN (950 -1450);
FORCEPROP 1 LAST SCH_ADDRESS2 P.O. BOX 58119
J 0
(950 -1500);
DISPLAY 0.617021 (950 -1500);
PAINT GREEN (950 -1500);
FORCEPROP 1 LAST SCH_ADDRESS3 Santa Clara, CA 95052-8119
J 0
(950 -1550);
DISPLAY 0.617021 (950 -1550);
PAINT GREEN (950 -1550);
FORCEPROP 1 LAST SCH_REV 2.420
J 0
(4675 -1425);
DISPLAY 0.978723 (4675 -1425);
PAINT YELLOW (4675 -1425);
FORCEPROP 2 LAST ROOM CPU0_CORE_VR
J 0
(-3175 3525);
DISPLAY 1.936170 (-3175 3525);
PAINT ORANGE (-3175 3525);
DISPLAY INVISIBLE (-3175 3525);
FORCEPROP 2 LAST PAGE_BORDER TRUE
J 0
(-2965 3675);
DISPLAY 1.255319 (-2965 3675);
PAINT PINK (-2965 3675);
DISPLAY INVISIBLE (-2965 3675);
FORCEPROP 1 LAST COMMENT_BODY TRUE
J 0
(4937 -1563);
DISPLAY 0.893617 (4937 -1563);
PAINT GREEN (4937 -1563);
DISPLAY INVISIBLE (4937 -1563);
FORCEPROP 2 LAST CDS_LIB mstr_symbols
J 0
(4925 -1575);
DISPLAY 1.936170 (4925 -1575);
PAINT ORANGE (4925 -1575);
DISPLAY INVISIBLE (4925 -1575);
FORCEPROP 2 LAST CDS_XR_PAGE_TITLE CR-216 : @BASEBOARD_FAB2_LIB.BASEBOARD_FAB2(SCH_1):PAGE216
J 0
(-2965 3675);
DISPLAY 0.638298 (-2965 3675);
PAINT PINK (-2965 3675);
DISPLAY INVISIBLE (-2965 3675);
WIRE 16 -1 (925 2400)(800 2400);
WIRE 16 -1 (800 2400)(800 1125);
WIRE 16 -1 (800 1125)(3500 1125);
WIRE 16 -1 (3500 1125)(3500 1950);
WIRE 16 -1 (3275 1950)(3500 1950);
WIRE 16 -1 (3500 1950)(4000 1950);
WIRE 16 -1 (4000 1850)(4000 1950);
WIRE 16 -1 (4000 1950)(4000 2000);
WIRE 16 -1 (4225 2150)(4225 2300);
WIRE 16 -1 (4325 -100)(4325 -175);
WIRE 16 -1 (675 1650)(675 1550);
WIRE 16 -1 (775 -725)(775 -825);
WIRE 16 -1 (2750 1350)(2750 1275);
WIRE 16 -1 (2650 2225)(2650 2175);
WIRE 16 -1 (2700 -1025)(2700 -1100);
WIRE 16 -1 (2550 -225)(2550 -275);
WIRE 16 -1 (1925 1850)(2100 1850);
WIRE 16 -1 (2100 1800)(2100 1850);
WIRE 16 -1 (2100 1750)(2100 1800);
WIRE 16 -1 (2100 1800)(1925 1800);
WIRE 16 -1 (2100 1700)(2100 1750);
WIRE 16 -1 (2100 1750)(1925 1750);
WIRE 16 -1 (1925 1700)(2100 1700);
WIRE 16 -1 (2100 1625)(2100 1700);
WIRE 16 -1 (-500 2425)(-500 2200);
WIRE 16 -1 (-500 2200)(-675 2200);
WIRE 16 -1 (-675 2400)(-675 2200);
WIRE 16 -1 (-1400 2200)(-675 2200);
WIRE 16 -1 (-1400 2375)(-1400 2200);
WIRE 16 -1 (-1400 2200)(-1650 2200);
WIRE 16 -1 (-1650 2375)(-1650 2200);
WIRE 16 -1 (-1650 2200)(-1900 2200);
WIRE 16 -1 (-1900 2375)(-1900 2200);
WIRE 16 -1 (-1900 2200)(-2150 2200);
WIRE 16 -1 (-2150 2450)(-2150 2200);
WIRE 16 -1 (-2150 2200)(-2425 2200);
WIRE 16 -1 (-2425 2425)(-2425 2200);
WIRE 16 -1 (-2425 2200)(-2675 2200);
WIRE 16 -1 (-2675 2425)(-2675 2200);
WIRE 16 -1 (-2675 2125)(-2675 2200);
WIRE 16 -1 (925 25)(850 25);
WIRE 16 -1 (850 25)(850 -1175);
WIRE 16 -1 (850 -1175)(3400 -1175);
WIRE 16 -1 (3400 -1175)(3400 -425);
WIRE 16 -1 (3225 -425)(3400 -425);
WIRE 16 -1 (3400 -425)(4050 -425);
WIRE 16 -1 (4050 -525)(4050 -425);
WIRE 16 -1 (4050 -425)(4050 -375);
WIRE 16 -1 (4050 -800)(4050 -725);
WIRE 16 -1 (4000 1575)(4000 1650);
WIRE 16 -1 (1925 -525)(2100 -525);
WIRE 16 -1 (2100 -575)(2100 -525);
WIRE 16 -1 (2100 -625)(2100 -575);
WIRE 16 -1 (2100 -575)(1925 -575);
WIRE 16 -1 (2100 -675)(2100 -625);
WIRE 16 -1 (2100 -625)(1925 -625);
WIRE 16 -1 (2100 -825)(2100 -675);
WIRE 16 -1 (2100 -675)(1925 -675);
WIRE 16 -1 (925 375)(725 375);
WIRE 16 -1 (725 375)(725 325);
WIRE 16 -1 (925 325)(725 325);
WIRE 16 -1 (725 325)(-1675 325);
WIRE 16 -1 (-1675 200)(-1675 325);
WIRE 16 -1 (-1675 325)(-1900 325);
WIRE 16 -1 (-1900 225)(-1900 325);
WIRE 16 -1 (-1900 325)(-2125 325);
WIRE 16 -1 (-2125 200)(-2125 325);
WIRE 16 -1 (-2125 325)(-2350 325);
WIRE 16 -1 (-2350 225)(-2350 325);
WIRE 16 -1 (-2350 325)(-2600 325);
WIRE 16 -1 (-2600 200)(-2600 325);
WIRE 16 -1 (-2600 625)(-2600 325);
WIRE 16 -1 (-450 50)(-450 -150);
WIRE 16 -1 (-450 -150)(-575 -150);
WIRE 16 -1 (-575 50)(-575 -150);
WIRE 16 -1 (-575 -150)(-1450 -150);
WIRE 16 -1 (-1450 25)(-1450 -150);
WIRE 16 -1 (-1450 -150)(-1675 -150);
WIRE 16 -1 (-1675 0)(-1675 -150);
WIRE 16 -1 (-1675 -150)(-1900 -150);
WIRE 16 -1 (-1900 25)(-1900 -150);
WIRE 16 -1 (-1900 -150)(-2125 -150);
WIRE 16 -1 (-2125 0)(-2125 -150);
WIRE 16 -1 (-2125 -150)(-2350 -150);
WIRE 16 -1 (-2350 25)(-2350 -150);
WIRE 16 -1 (-2350 -150)(-2600 -150);
WIRE 16 -1 (-2600 0)(-2600 -150);
WIRE 16 -1 (-2600 -225)(-2600 -150);
WIRE 16 -1 (925 2750)(725 2750);
WIRE 16 -1 (725 2750)(725 2700);
WIRE 16 -1 (925 2700)(725 2700);
WIRE 16 -1 (725 2700)(-1650 2700);
WIRE 16 -1 (-1650 2575)(-1650 2700);
WIRE 16 -1 (-1650 2700)(-1900 2700);
WIRE 16 -1 (-1900 2575)(-1900 2700);
WIRE 16 -1 (-1900 2700)(-2150 2700);
WIRE 16 -1 (-2150 2650)(-2150 2700);
WIRE 16 -1 (-2150 2700)(-2425 2700);
WIRE 16 -1 (-2425 2625)(-2425 2700);
WIRE 16 -1 (-2675 2700)(-2425 2700);
WIRE 16 -1 (-2675 2625)(-2675 2700);
WIRE 16 -1 (-2675 2800)(-2675 2700);
WIRE 16 -1 (925 2500)(850 2500);
WIRE 16 -1 (850 2500)(850 2600);
WIRE 16 -1 (850 2600)(925 2600);
WIRE 16 -1 (0 2600)(850 2600);
WIRE 16 -1 (0 3050)(0 2600);
WIRE 16 -1 (0 3050)(-500 3050);
WIRE 16 -1 (0 3050)(0 3150);
WIRE 16 -1 (-500 3050)(-675 3050);
WIRE 16 -1 (-500 2625)(-500 3050);
WIRE 16 -1 (-675 2600)(-675 3050);
WIRE 16 -1 (-675 3050)(-1075 3050);
WIRE 16 -1 (925 125)(825 125);
WIRE 16 -1 (825 125)(825 225);
WIRE 16 -1 (825 225)(925 225);
WIRE 16 -1 (150 225)(825 225);
WIRE 16 -1 (150 675)(150 225);
WIRE 16 -1 (-450 675)(150 675);
WIRE 16 -1 (150 800)(150 675);
WIRE 16 -1 (-450 675)(-575 675);
WIRE 16 -1 (-450 250)(-450 675);
WIRE 16 -1 (-575 250)(-575 675);
WIRE 16 -1 (-575 675)(-1100 675);
WIRE 3 2175 (2475 1175)(2875 1175);
WIRE 3 2175 (2475 2000)(2475 1175);
WIRE 3 2175 (2875 2000)(2875 1175);
WIRE 3 2175 (2475 2000)(2875 2000);
WIRE 3 2175 (2450 -375)(2925 -375);
WIRE 3 2175 (2450 -375)(2450 -1225);
WIRE 3 2175 (2925 -375)(2925 -1225);
WIRE 3 2175 (2450 -1225)(2925 -1225);
WIRE 16 -1 (-1150 -575)(-1150 -625);
WIRE 16 -1 (-1150 -625)(650 -625);
FORCEPROP 2 LAST SIG_NAME VR_PVDDQ_ABC_PH2_PHASE
J 0
(-1140 -615);
DISPLAY 0.617021 (-1140 -615);
PAINT ORANGE (-1140 -615);
FORCEPROP 2 LASTPROP $XRERR UNIQUE?
J 0
(-1380 -615);
DISPLAY 0.638298 (-1380 -615);
PAINT MONO (-1380 -615);
DISPLAY INVISIBLE (-1380 -615);
WIRE 16 -1 (650 -475)(650 -625);
WIRE 16 -1 (925 -475)(650 -475);
WIRE 3 2175 (-475 -500)(-50 -500);
WIRE 3 2175 (-475 -250)(-475 -500);
WIRE 3 2175 (-50 -250)(-50 -500);
WIRE 3 2175 (-475 -250)(-50 -250);
WIRE 3 2175 (500 -375)(1025 -375);
WIRE 3 2175 (500 -375)(500 -925);
WIRE 3 2175 (1025 -375)(1025 -925);
WIRE 3 2175 (500 -925)(1025 -925);
WIRE 16 -1 (-50 -75)(925 -75);
FORCEPROP 0 LAST SIG_NAME TP_PVDDQ_ABC_PH2_GL_1
J 0
(-23 -60);
DISPLAY 0.617021 (-23 -60);
PAINT ORANGE (-23 -60);
FORCEPROP 2 LASTPROP $XRERR UNIQUE?
J 0
(-290 -75);
DISPLAY 0.638298 (-290 -75);
PAINT MONO (-290 -75);
DISPLAY INVISIBLE (-290 -75);
WIRE 16 2175 (-900 300)(-200 300);
WIRE 16 2175 (-900 300)(-900 -100);
WIRE 16 2175 (-200 300)(-200 -100);
WIRE 16 2175 (-900 -100)(-200 -100);
WIRE 16 -1 (-1450 425)(925 425);
FORCEPROP 2 LAST SIG_NAME VR_PVDDQ_ABC_PH2_VCIN
J 0
(-1390 435);
DISPLAY 0.617021 (-1390 435);
PAINT ORANGE (-1390 435);
FORCEPROP 2 LASTPROP $XRERR UNIQUE?
J 0
(-1630 435);
DISPLAY 0.638298 (-1630 435);
PAINT MONO (-1630 435);
DISPLAY INVISIBLE (-1630 435);
WIRE 16 -1 (-1450 675)(-1450 425);
WIRE 16 -1 (-1450 225)(-1450 425);
WIRE 16 -1 (-1450 675)(-1300 675);
WIRE 16 -1 (2750 1725)(2750 1600);
WIRE 16 -1 (1925 1950)(2750 1950);
FORCEPROP 2 LAST SIG_NAME VR_PVDDQ_ABC_PH1_SW
J 0
(1985 1960);
DISPLAY 0.617021 (1985 1960);
PAINT ORANGE (1985 1960);
FORCEPROP 2 LASTPROP $XRERR UNIQUE?
J 0
(1745 1960);
DISPLAY 0.638298 (1745 1960);
PAINT MONO (1745 1960);
DISPLAY INVISIBLE (1745 1960);
WIRE 16 -1 (2750 1950)(3075 1950);
WIRE 16 -1 (2750 1875)(2750 1950);
WIRE 3 2175 (2425 2525)(2900 2525);
WIRE 3 2175 (2425 2525)(2425 2050);
WIRE 3 2175 (2900 2525)(2900 2050);
WIRE 3 2175 (2425 2050)(2900 2050);
WIRE 3 2175 (2325 125)(2800 125);
WIRE 3 2175 (2325 125)(2325 -350);
WIRE 3 2175 (2800 125)(2800 -350);
WIRE 3 2175 (2325 -350)(2800 -350);
WIRE 16 -1 (1925 -425)(2700 -425);
FORCEPROP 2 LAST SIG_NAME VR_PVDDQ_ABC_PH2_SW
J 0
(2010 -415);
DISPLAY 0.617021 (2010 -415);
PAINT ORANGE (2010 -415);
FORCEPROP 2 LASTPROP $XRERR UNIQUE?
J 0
(1770 -415);
DISPLAY 0.638298 (1770 -415);
PAINT MONO (1770 -415);
DISPLAY INVISIBLE (1770 -415);
WIRE 16 -1 (2700 -425)(3025 -425);
WIRE 16 -1 (2700 -525)(2700 -425);
WIRE 16 -1 (2700 -775)(2700 -675);
WIRE 16 -1 (-125 -325)(650 -325);
FORCEPROP 2 LAST SIG_NAME VR_PVDDQ_ABC_PH2_BOOT_R
J 0
(-40 -315);
DISPLAY 0.617021 (-40 -315);
PAINT ORANGE (-40 -315);
FORCEPROP 2 LASTPROP $XRERR UNIQUE?
J 0
(-280 -315);
DISPLAY 0.638298 (-280 -315);
PAINT MONO (-280 -315);
DISPLAY INVISIBLE (-280 -315);
WIRE 16 -1 (650 -425)(650 -325);
WIRE 16 -1 (925 -425)(650 -425);
WIRE 16 -1 (-325 -325)(-1150 -325);
FORCEPROP 2 LAST SIG_NAME VR_PVDDQ_ABC_PH2_BOOT
J 0
(-1115 -315);
DISPLAY 0.617021 (-1115 -315);
PAINT ORANGE (-1115 -315);
FORCEPROP 2 LASTPROP $XRERR UNIQUE?
J 0
(-1355 -315);
DISPLAY 0.638298 (-1355 -315);
PAINT MONO (-1355 -315);
DISPLAY INVISIBLE (-1355 -315);
WIRE 16 -1 (-1150 -325)(-1150 -375);
WIRE 16 2175 (-1325 -650)(-600 -650);
WIRE 16 2175 (-1325 -225)(-1325 -650);
WIRE 16 2175 (-600 -225)(-600 -650);
WIRE 16 -1 (-1325 -225)(-600 -225);
WIRE 16 -1 (-600 -225)(925 -225);
WIRE 16 -1 (-1750 -225)(-1325 -225);
FORCEPROP 2 LAST SIG_NAME VR_PVDDQ_ABC_PWM2
J 0
(-1763 -215);
DISPLAY 0.617021 (-1763 -215);
PAINT ORANGE (-1763 -215);
WIRE 16 -1 (2650 2450)(3225 2450);
WIRE 16 -1 (2650 2450)(2650 2425);
WIRE 16 -1 (2000 2450)(2650 2450);
FORCEPROP 2 LAST SIG_NAME A_TSENSE_PVDDQ_ABC
J 0
(2012 2460);
DISPLAY 0.617021 (2012 2460);
PAINT ORANGE (2012 2460);
WIRE 16 -1 (2000 2300)(2000 2450);
WIRE 16 -1 (1925 2300)(2000 2300);
WIRE 16 -1 (1925 2600)(4225 2600);
FORCEPROP 0 LAST VOLTAGE 3.6
J 0
(2000 2675);
DISPLAY 1.021277 (2000 2675);
PAINT SKYBLUE (2000 2675);
DISPLAY INVISIBLE (2000 2675);
FORCEPROP 2 LAST SIG_NAME VR_PVDDQ_ABC_PH1_OCSET
J 0
(2057 2616);
DISPLAY 0.617021 (2057 2616);
PAINT ORANGE (2057 2616);
FORCEPROP 2 LASTPROP $XRERR UNIQUE?
J 0
(1817 2616);
DISPLAY 0.638298 (1817 2616);
PAINT MONO (1817 2616);
DISPLAY INVISIBLE (1817 2616);
WIRE 16 -1 (4225 2500)(4225 2600);
WIRE 3 2175 (450 2000)(1025 2000);
WIRE 3 2175 (450 2000)(450 1475);
WIRE 3 2175 (1025 2000)(1025 1475);
WIRE 3 2175 (450 1475)(1025 1475);
WIRE 16 -1 (-1025 1750)(550 1750);
FORCEPROP 2 LAST SIG_NAME VR_PVDDQ_ABC_PH1_PHASE
J 0
(-1015 1760);
DISPLAY 0.617021 (-1015 1760);
PAINT ORANGE (-1015 1760);
FORCEPROP 2 LASTPROP $XRERR UNIQUE?
J 0
(-1255 1760);
DISPLAY 0.638298 (-1255 1760);
PAINT MONO (-1255 1760);
DISPLAY INVISIBLE (-1255 1760);
WIRE 16 -1 (-1025 1750)(-1025 1775);
WIRE 16 -1 (550 1750)(550 1900);
WIRE 16 -1 (550 1900)(925 1900);
WIRE 16 -1 (-175 2025)(550 2025);
FORCEPROP 2 LAST SIG_NAME VR_PVDDQ_ABC_PH1_BOOT_R
J 0
(-40 2035);
DISPLAY 0.617021 (-40 2035);
PAINT ORANGE (-40 2035);
FORCEPROP 2 LASTPROP $XRERR UNIQUE?
J 0
(-280 2035);
DISPLAY 0.638298 (-280 2035);
PAINT MONO (-280 2035);
DISPLAY INVISIBLE (-280 2035);
WIRE 16 -1 (550 2025)(550 1950);
WIRE 16 -1 (550 1950)(925 1950);
WIRE 16 -1 (925 2050)(675 2050);
WIRE 16 -1 (675 2050)(675 3125);
WIRE 16 -1 (675 1850)(675 2050);
WIRE 16 -1 (675 3125)(3200 3125);
FORCEPROP 2 LAST SIG_NAME VR_PVDDQ_ABC_AIREF1
J 0
(2550 3135);
DISPLAY 0.617021 (2550 3135);
PAINT ORANGE (2550 3135);
WIRE 3 2175 (-425 2100)(-50 2100);
WIRE 3 2175 (-425 2100)(-425 1875);
WIRE 3 2175 (-50 2100)(-50 1875);
WIRE 3 2175 (-425 1875)(-50 1875);
WIRE 16 -1 (-375 2025)(-1025 2025);
FORCEPROP 2 LAST SIG_NAME VR_PVDDQ_ABC_PH1_BOOT
J 0
(-1015 2035);
DISPLAY 0.617021 (-1015 2035);
PAINT ORANGE (-1015 2035);
FORCEPROP 2 LASTPROP $XRERR UNIQUE?
J 0
(-1255 2035);
DISPLAY 0.638298 (-1255 2035);
PAINT MONO (-1255 2035);
DISPLAY INVISIBLE (-1255 2035);
WIRE 16 -1 (-1025 2025)(-1025 1975);
WIRE 16 2175 (-1350 2075)(-525 2075);
WIRE 16 2175 (-1350 2075)(-1350 1675);
WIRE 16 2175 (-525 2075)(-525 1675);
WIRE 16 2175 (-1350 1675)(-525 1675);
WIRE 16 -1 (1925 225)(4325 225);
FORCEPROP 0 LAST VOLTAGE 3.6
J 0
(2000 300);
DISPLAY 1.021277 (2000 300);
PAINT SKYBLUE (2000 300);
DISPLAY INVISIBLE (2000 300);
FORCEPROP 2 LAST SIG_NAME VR_PVDDQ_ABC_PH2_OCSET
J 0
(2057 241);
DISPLAY 0.617021 (2057 241);
PAINT ORANGE (2057 241);
FORCEPROP 2 LASTPROP $XRERR UNIQUE?
J 0
(1817 241);
DISPLAY 0.638298 (1817 241);
PAINT MONO (1817 241);
DISPLAY INVISIBLE (1817 241);
WIRE 16 -1 (4325 225)(4325 100);
WIRE 16 2175 (-950 2650)(-250 2650);
WIRE 16 2175 (-950 2650)(-950 2250);
WIRE 16 2175 (-250 2650)(-250 2250);
WIRE 16 2175 (-950 2250)(-250 2250);
WIRE 16 -1 (-1825 2150)(925 2150);
WIRE 16 -1 (3075 750)(775 750);
FORCEPROP 2 LAST SIG_NAME VR_PVDDQ_ABC_AIREF2
J 0
(2411 748);
DISPLAY 0.617021 (2411 748);
PAINT ORANGE (2411 748);
WIRE 16 -1 (775 -325)(775 750);
WIRE 16 -1 (925 -325)(775 -325);
WIRE 16 -1 (775 -525)(775 -325);
WIRE 16 -1 (1925 50)(2550 50);
FORCEPROP 2 LAST SIG_NAME A_TSENSE_PVDDQ_ABC
J 0
(1937 60);
DISPLAY 0.617021 (1937 60);
PAINT ORANGE (1937 60);
WIRE 16 -1 (1925 50)(1925 -75);
WIRE 16 -1 (2550 50)(3225 50);
WIRE 16 -1 (2550 -25)(2550 50);
WIRE 16 -1 (1925 425)(3075 425);
FORCEPROP 2 LAST SIG_NAME ISENSE_PVDDQ_ABC_PH2_IMON
J 0
(2237 435);
DISPLAY 0.617021 (2237 435);
PAINT ORANGE (2237 435);
WIRE 16 -1 (2650 2550)(1925 2550);
FORCEPROP 2 LAST SIG_NAME NC_PVDDQ_ABC_PH1_P31
J 0
(2112 2560);
DISPLAY 0.617021 (2112 2560);
PAINT ORANGE (2112 2560);
FORCEPROP 2 LASTPROP $XRERR UNIQUE?
J 0
(2680 2550);
DISPLAY 0.638298 (2680 2550);
PAINT MONO (2680 2550);
DISPLAY INVISIBLE (2680 2550);
WIRE 16 -1 (-50 -125)(925 -125);
FORCEPROP 0 LAST SIG_NAME TP_PVDDQ_ABC_PH2_GL_0
J 0
(-23 -110);
DISPLAY 0.617021 (-23 -110);
PAINT ORANGE (-23 -110);
FORCEPROP 2 LASTPROP $XRERR UNIQUE?
J 0
(-290 -125);
DISPLAY 0.638298 (-290 -125);
PAINT MONO (-290 -125);
DISPLAY INVISIBLE (-290 -125);
WIRE 16 -1 (1925 175)(3050 175);
FORCEPROP 2 LAST SIG_NAME NC_PVDDQ_ABC_PH2_P31
J 0
(2087 185);
DISPLAY 0.617021 (2087 185);
PAINT ORANGE (2087 185);
FORCEPROP 2 LASTPROP $XRERR UNIQUE?
J 0
(3080 175);
DISPLAY 0.638298 (3080 175);
PAINT MONO (3080 175);
DISPLAY INVISIBLE (3080 175);
WIRE 16 -1 (-50 2300)(925 2300);
FORCEPROP 0 LAST SIG_NAME TP_PVDDQ_ABC_PH1_GL_1
J 0
(-23 2315);
DISPLAY 0.617021 (-23 2315);
PAINT ORANGE (-23 2315);
FORCEPROP 2 LASTPROP $XRERR UNIQUE?
J 0
(-290 2300);
DISPLAY 0.638298 (-290 2300);
PAINT MONO (-290 2300);
DISPLAY INVISIBLE (-290 2300);
WIRE 16 -1 (-50 2250)(925 2250);
FORCEPROP 0 LAST SIG_NAME TP_PVDDQ_ABC_PH1_GL_0
J 0
(-23 2265);
DISPLAY 0.617021 (-23 2265);
PAINT ORANGE (-23 2265);
FORCEPROP 2 LASTPROP $XRERR UNIQUE?
J 0
(-290 2250);
DISPLAY 0.638298 (-290 2250);
PAINT MONO (-290 2250);
DISPLAY INVISIBLE (-290 2250);
WIRE 16 -1 (-1400 2575)(-1400 2800);
WIRE 16 -1 (-1400 2800)(925 2800);
FORCEPROP 2 LAST SIG_NAME VR_PVDDQ_ABC_PH1_VCIN
J 0
(-1365 2810);
DISPLAY 0.617021 (-1365 2810);
PAINT ORANGE (-1365 2810);
FORCEPROP 2 LASTPROP $XRERR UNIQUE?
J 0
(-1605 2810);
DISPLAY 0.638298 (-1605 2810);
PAINT MONO (-1605 2810);
DISPLAY INVISIBLE (-1605 2810);
WIRE 16 -1 (-1400 2800)(-1400 3050);
WIRE 16 -1 (-1400 3050)(-1275 3050);
WIRE 16 -1 (1925 2800)(3225 2800);
FORCEPROP 2 LAST SIG_NAME ISENSE_PVDDQ_ABC_PH1_IMON
J 0
(2237 2810);
DISPLAY 0.617021 (2237 2810);
PAINT ORANGE (2237 2810);
DOT 1 (2700 -425);
DOT 1 (-1325 -225);
DOT 1 (-600 -225);
DOT 1 (4000 1950);
DOT 1 (3500 1950);
DOT 1 (725 2700);
DOT 1 (825 225);
DOT 1 (725 325);
DOT 1 (150 675);
DOT 1 (4050 -425);
DOT 1 (2100 -625);
DOT 1 (2100 -575);
DOT 1 (2100 -675);
DOT 1 (0 3050);
DOT 1 (-500 3050);
DOT 1 (-675 3050);
DOT 1 (-675 2200);
DOT 1 (-1400 2200);
DOT 1 (-1650 2700);
DOT 1 (-1900 2700);
DOT 1 (-1650 2200);
DOT 1 (-1900 2200);
DOT 1 (-450 675);
DOT 1 (-575 675);
DOT 1 (-1450 425);
DOT 1 (-1675 325);
DOT 1 (-1900 325);
DOT 1 (-2150 2700);
DOT 1 (-2425 2700);
DOT 1 (-2150 2200);
DOT 1 (-2425 2200);
DOT 1 (-2675 2700);
DOT 1 (-2675 2200);
DOT 1 (-2125 325);
DOT 1 (-2350 325);
DOT 1 (-2600 325);
DOT 1 (-575 -150);
DOT 1 (-1450 -150);
DOT 1 (-1675 -150);
DOT 1 (-1900 -150);
DOT 1 (-2125 -150);
DOT 1 (-2350 -150);
DOT 1 (-2600 -150);
DOT 1 (3400 -425);
DOT 1 (775 -325);
DOT 1 (2550 50);
DOT 1 (-1400 2800);
DOT 1 (850 2600);
DOT 1 (675 2050);
DOT 1 (2100 1800);
DOT 1 (2100 1750);
DOT 1 (2100 1700);
DOT 1 (2650 2450);
DOT 1 (2750 1950);
FORCENOTE
TP FAB1 3.01 OHM NEED CHANGE TO 2.2 OHM BUT WAIT FOR SYMBOL
(2925 -1075) 0;
DISPLAY LEFT (2925 -1075);
DISPLAY 0.851064 (2925 -1075);
PAINT RED (2925 -1075);
FORCENOTE
TP FAB1CO-LAY WITH TI PARTS 11/16
(2925 -1025) 0;
DISPLAY LEFT (2925 -1025);
DISPLAY 0.851064 (2925 -1025);
PAINT RED (2925 -1025);
FORCENOTE
TP FAB1 3.01 OHM NEED CHANGE TO 2.2 OHM BUT WAIT FOR SYMBOL
(2925 1275) 0;
DISPLAY LEFT (2925 1275);
DISPLAY 0.851064 (2925 1275);
PAINT RED (2925 1275);
FORCENOTE
TP FAB1 CO-LAY WITH TI PARTS 11/16
(2925 1325) 0;
DISPLAY LEFT (2925 1325);
DISPLAY 0.851064 (2925 1325);
PAINT RED (2925 1325);
FORCENOTE
TP FAB1 CO-LAY WITH TI PARTS 11/16
(2850 -175) 0;
DISPLAY LEFT (2850 -175);
DISPLAY 0.851064 (2850 -175);
PAINT RED (2850 -175);
FORCENOTE
TP FAB1 CO-LAY WITH TI PARTS 11/16
(2925 2250) 0;
DISPLAY LEFT (2925 2250);
DISPLAY 1.021277 (2925 2250);
PAINT RED (2925 2250);
FORCENOTE
SPOF
(-980 -850) 0;
DISPLAY LEFT (-980 -850);
DISPLAY 1.808511 (-980 -850);
PAINT PURPLE (-980 -850);
FORCENOTE
TP FAB1 CO-LAY WITH TI PARTS 11/16
(-475 1500) 0;
DISPLAY LEFT (-475 1500);
DISPLAY 0.851064 (-475 1500);
PAINT RED (-475 1500);
FORCENOTE
SPOF
(-880 1575) 0;
DISPLAY LEFT (-880 1575);
DISPLAY 1.936170 (-880 1575);
PAINT PURPLE (-880 1575);
FORCENOTE
PLACE ON TOP
(-955 2175) 0;
DISPLAY LEFT (-955 2175);
DISPLAY 1.553191 (-955 2175);
PAINT PURPLE (-955 2175);
FORCENOTE
PLACE ON TOP
(-905 -175) 0;
DISPLAY LEFT (-905 -175);
DISPLAY 1.553191 (-905 -175);
PAINT PURPLE (-905 -175);
FORCENOTE
TP FAB1 CO-LAY WITH TI PARTS 11/16
(-550 -825) 0;
DISPLAY LEFT (-550 -825);
DISPLAY 0.851064 (-550 -825);
PAINT RED (-550 -825);
FORCENOTE
ROOM = VDDQ_ABC_PWR_VR
(-3005 -1400) 0;
DISPLAY LEFT (-3005 -1400);
DISPLAY 2.893617 (-3005 -1400);
PAINT PURPLE (-3005 -1400);
QUIT
